5
5
4
4
3
3
2
2
1
1
D D
C C
B B
A A
Honey Badger 
uServer Model 
Title 
Size Document Number Rev 
Date: Sheet o f 
Honey_Badger_uServer 1B
COVER PAGE
A
1 56Tuesday, January 20, 2015
Wiwynn Incorporated
http://www.wiwynn.com
8F, 90, Sec.1, Xintai 5th Rd., Xizhi Dist.,
New Taipei City 22102, Taiwan (R.O.C.)
Title 
Size Document Number Rev 
Date: Sheet o f 
Honey_Badger_uServer 1B
COVER PAGE
A
1 56Tuesday, January 20, 2015
Wiwynn Incorporated
http://www.wiwynn.com
8F, 90, Sec.1, Xintai 5th Rd., Xizhi Dist.,
New Taipei City 22102, Taiwan (R.O.C.)
Title 
Size Document Number Rev 
Date: Sheet o f 
Honey_Badger_uServer 1B
COVER PAGE
A
1 56Tuesday, January 20, 2015
Wiwynn Incorporated
http://www.wiwynn.com
8F, 90, Sec.1, Xintai 5th Rd., Xizhi Dist.,
New Taipei City 22102, Taiwan (R.O.C.)



5
5
4
4
3
3
2
2
1
1
D D
C C
B B
A A
ISOLATION CIRCUITTY 
SPI REMOTE FLASH CHB0 SO-DIMM SOCKET CPU GND(2/2) CPU DDR CHA TABLE OF CONTENTS CLOCK DIAGRAM STANDBY POWER POWER DISTRIBUTION DIAGRAM I2C TOPOLOGY POWER SEQUENCE SYSTEM BLOCK DIAGRAM NORMAL POWER 
52 51 50 53 
40 
47 44 43 41 42 
12 39 
45 48 
PWRSW_P1V8_STBY & P1V8 
49 46 
17 16 15 14 13 22 21 20 19 18 30 29 28 27 24 23 05 04 03 02 31 10 11 08 09 06 33 32 07 34 26 25 37 36 01 
COVER PAGE 
35 38 
M-SATA CONNECT CHB1 SO-DIMM SOCKET I2C SENSOR DEVICE CLOCK BUFFER CLOCK GEN 4420 DIMM VREF FPGA POWER&GND (3/3) FPGA I/O PORT(2/3) FPGA I/O PORT(1/3) PCIe GOLD FINGER JTAG CHAIN 
PWR_2V5&1V2_STBY PWR_1V5_STBY PWRSW_P3V3_STBY PWRSW_PVCCP & PVNN PWRSW_P1V0_STBY PWRLDO_PV_VTT_DDR PWRSW_PV_VDDR 
NGFF CPU GB LAN CPU SMB/LPC/SVID PULL-UP CPU MISC SIGNAL CPU PCI-E CPU XDP CONN CPU INDICATOR LED CPU LEVEL SHIFT CPU GND(1/2) CPU POWER(2/2) CPU POWER(1/2) CPU DDR CH-B BLANK CHA1 SO-DIMM SOCKET CHA0 SO-DIMM SOCKET 
TABLE OF CONTENTS 
PWRSW_P3V3_CPU & P3V3 
PAGE TITLE 
PAGE TITLE 
PAGE 
PAGE 
CPU SATA/USB/DFX/BOARD REV 
PWRSW_P1V35 PWRSW_P1V1 PWRSW_P1V0 
562R2F- GP 
562 = 562 ohm, (2K2R means 2.2K ohm) 
2 = size 0402 
F = 1% tolerance 
GP= Green Part (RoHS) 
RC size code as below: 
1 = 0201 
2= 0402 
3= 0603 
5= 0805 
6= 1206 
R tolerance code as below: 
D=0.5% 
F= 1% 
J= 5% 
SCD1U10V2KX-5GP 
D1U = 0.1uF (2D2U means 2.2uF) 
10Voltage (6D3V means 6.3V) 
2 = size 0402, K tolerance 
K=tolerance 
[C code as below:] 
G=2% 
J=5% 
K=10% 
M=20% 
X=temp characteristics 
[C Series/Temp] 
N=NPO 
X=X7R/X5R 
Y=Y5V 
-5=different symbol/customer 
GP= Green Part (RoHS) 
54 55 
BLANK BLANK 
56 
BLANK 
Title 
Size Document Number R e v 
Date: Sheet 
o f 
Honey_Badger_uServer 1B
TABLE OF CONTENTS
A3
2 56Tuesday, January 20, 2015
Wiwynn Incorporated
http://www.wiwynn.com
8F, 90, Sec.1, Xintai 5th Rd., Xizhi Dist.,
New Taipei City 22102, Taiwan (R.O.C.)
Title 
Size Document Number R e v 
Date: Sheet 
o f 
Honey_Badger_uServer 1B
TABLE OF CONTENTS
A3
2 56Tuesday, January 20, 2015
Wiwynn Incorporated
http://www.wiwynn.com
8F, 90, Sec.1, Xintai 5th Rd., Xizhi Dist.,
New Taipei City 22102, Taiwan (R.O.C.)
Title 
Size Document Number R e v 
Date: Sheet 
o f 
Honey_Badger_uServer 1B
TABLE OF CONTENTS
A3
2 56Tuesday, January 20, 2015
Wiwynn Incorporated
http://www.wiwynn.com
8F, 90, Sec.1, Xintai 5th Rd., Xizhi Dist.,
New Taipei City 22102, Taiwan (R.O.C.)



5
5
4
4
3
3
2
2
1
1
D D
C C
B B
A A
Honey Badger uServer Block Diagram 
    CPU 
 Avoton 
 4/8 core 
  2.4GHz 
XDP CONN 
Flash 
(BIOS) 
SPI 
DDR3 CHA 
SO-DIMM 
(Slot0) 
SO-DIMM 
(Slot1) 
DDR3 CHB 
SO-DIMM 
(Slot0) 
SO-DIMM 
(Slot1) 
mSATA 
  SSD 
NGFF 
Flash 
PCIe2 x4/ 
SATA3 
FPGA LPC 
SMBus 
GPIO 
Clock Gen& 
Clock Buffer 
Clock 
EEPROM 
SPI 
PCIe X16 
PCIe2  x8  (Storage) 
SATA2 x1 
UART(Serial Tx/Rx) 
I2C 
EEPROM 
TEMP SENSOR 
Onboard VRs 
12V 
VOLTAGE 
SENSOR x1 
SerDes(1GbE) x1 
USB x1 
PCIe2  x4  (10G Ethernet) 
Slot ID/ HW Rev 
I2C_Alert# 
PCIECLK 
PCIERST# 
SYSRST# 
PWRON 
SATA3 ECC SO-DIMM DDR3-1600 
X4 for 32GB/ x2 for 16GB 
PWR & SYS LED 
Beep LED 
All VRs Power Good 
Diagnotics LED 
GbE SMBUS 
I2C to SPI 
Switch 
Title 
Size Document Number R e v 
Date: Sheet 
o f 
Honey_Badger_uServer 1B
SYSTEM BLOCK DIAGRAM
A3
3 56Tuesday, January 20, 2015
Wiwynn Incorporated
http://www.wiwynn.com
8F, 90, Sec.1, Xintai 5th Rd., Xizhi Dist.,
New Taipei City 22102, Taiwan (R.O.C.)
Title 
Size Document Number R e v 
Date: Sheet 
o f 
Honey_Badger_uServer 1B
SYSTEM BLOCK DIAGRAM
A3
3 56Tuesday, January 20, 2015
Wiwynn Incorporated
http://www.wiwynn.com
8F, 90, Sec.1, Xintai 5th Rd., Xizhi Dist.,
New Taipei City 22102, Taiwan (R.O.C.)
Title 
Size Document Number R e v 
Date: Sheet 
o f 
Honey_Badger_uServer 1B
SYSTEM BLOCK DIAGRAM
A3
3 56Tuesday, January 20, 2015
Wiwynn Incorporated
http://www.wiwynn.com
8F, 90, Sec.1, Xintai 5th Rd., Xizhi Dist.,
New Taipei City 22102, Taiwan (R.O.C.)



5
5
4
4
3
3
2
2
1
1
D D
C C
B B
A A
1.1V   2.8A 
P1V1 
P3V3_STBY 
P1V1 
PVCCP 
PV_VTT_DDR (0.675V) 0.8A 
PV_VDDR   (1.5/1.35V) 4A 
PVCCP        (0.5~1.3) 23.3A 
P1V0A     1.2A 
P1V0S       6.9A 
DDR3 DIMM 
Avoton CPU 
P3V3_STBY     28mA 
FPGA 
P3V3_S       50mA 
P2V5_S       50mA 
P1V2_S      200mA 
P1V0_STBY 
P3V3_CPU 
P3V3_STBY 
PVTT_A 
P2V5_STBY 
2.5V   50mA 
P=0.125W 
P1V2_STBY 
1.2V   200mA 
P=0.24W 
P2V5_STBY 
P1V2_STBY 
P1V8_A       100mA 
P1V8_S     100mA 
P3V3_STBY 
P3V3 
P12V 
SPI Flash 
Clock Generator 
P1V8_STBY 
P1V5_STBY 
1.5V 415mA 
P=0.6225W 
PV_VDDR(1.35V) 12A 
P1V5_STBY      40mA 
PVTT_DDRx2 
P1V35_S         200mA 
P3V3_A        80mA 
V3P3_S       80mA 
V3P3_RTC  1.2mA 
PVNN        (0.5~1.3) 2.2A 
P1V8 
P1V35 
VR12 sVID 
1.35V 12.1A 
PVDDR 
PVDDR 
0.675V  0.4x2A 
P1V0 
PVNN 
P3V3 
P3V3_S   25mA 
P3V3  1A 
mSATA 
P3V3_STBY 
3.3V   4.5A 
P1V8_STBY 
1.8V   1.04A 
P1V0_STBY 
1V   1.2A 
P1V35 
1.35V   34mA 
P=15.3mW 
PVCCP/PVNN 
23.3A/2.2A 
12.5V LOAD PSU 
CONNECTOR 
BATTERY 
CONNECTOR Hot Swap 
Current Limit 
VR SWITCHING 
P1V1         2.8A 
S0 support 
Ideal or low 
Vf diode S5 support 
VR LINEAR 
Low Rds on 
FET Switch 
P3V3 
Clock buf fer 
P3V3_STBY     40mA P3V3_STBY 
PVTT_B 
Bat tery 
PV_VDDR 
P1V0 
1.0V   6.9A 
P1V5_STBY 
P=0.54W 
P3V3_STBY 
P3V3  1.33A 
NGFF 
P3V3_STBY 
Title 
Size Document Number R ev 
Date: Sheet 
o f 
Honey_Badger_uServer 1B
POWER DISTRIBUTION DIAGRAM
Custom
4 56Tuesday, January 20, 2015
Wiwynn Incorporated
http://www.wiwynn.com
8F, 90, Sec.1, Xintai 5th Rd., Xizhi Dist.,
New Taipei City 22102, Taiwan (R.O.C.)
Title 
Size Document Number R ev 
Date: Sheet 
o f 
Honey_Badger_uServer 1B
POWER DISTRIBUTION DIAGRAM
Custom
4 56Tuesday, January 20, 2015
Wiwynn Incorporated
http://www.wiwynn.com
8F, 90, Sec.1, Xintai 5th Rd., Xizhi Dist.,
New Taipei City 22102, Taiwan (R.O.C.)
Title 
Size Document Number R ev 
Date: Sheet 
o f 
Honey_Badger_uServer 1B
POWER DISTRIBUTION DIAGRAM
Custom
4 56Tuesday, January 20, 2015
Wiwynn Incorporated
http://www.wiwynn.com
8F, 90, Sec.1, Xintai 5th Rd., Xizhi Dist.,
New Taipei City 22102, Taiwan (R.O.C.)



5
5
4
4
3
3
2
2
1
1
D D
C C
B B
A A
15kΩ 
CPU_RSMRST# 
10kΩ 
VDD 
2.2kΩ 
P3V3_STBY 
P3V3_STBY 
4.7U 
4.7KΩ 
P12V 
G
S
D
S
G
D
SG
D
LDO solution for FPGA 
1uF 
P3V3_STBY 
33Ω 
10kΩ 
VCC 
YA
A Y
GND 
CPU_RSMRST# 
CPU 
10kΩ 
P3V3_STBY_VREG(5V) 
TPS53318DQPR-GP 
P3V3_STBY 
EN 
In 
PGOOD 
OUT 
(OD) 
P12V 
Switching 
30kΩ 
P3V3_CPU 
P3V3_STBY 
10KΩ 
P12V 
PWRGD_P3V3_CPU_PG 
Standby Power 
PGOOD 
(OD) 
OUT 
P1V8_STBY 
PU13 
In 
EN 
EP53F8QI-T-GP 
Switching 
10kΩ 
P3V3_STBY 
LD1117AG 
P1V2_FPGA_D 
In OUT 
P3V3_STBY 
LDO 
TPS79301DBVR-GP 
P2V5_STBY 
In OUT 
P3V3_STBY 
LDO 
TPS74801RGW-GP 
P1V5_STBY 
EN 
In 
PGOOD 
OUT 
(OD) 
P1V8_STBY 
LDO 
LD1117AG 
P1V2_FPGA_A 
In OUT 
P3V3_STBY 
LDO 
PGOOD 
(OD) 
OUT 
P1V0_STBY 
PU11 
In 
EN 
EP53F8QI-T-GP 
Switching 
10kΩ 
P3V3_STBY 
10kΩ 
P3V3_STBY 
P12V 
PU15 
PU14 
VDD 
P12V 
VDD 
P3V3_STBY 
P3V3_STBY 
1uF 
Title 
Size Document Number Rev 
Date: Sheet o f 
Honey_Badger_uServer 1B
STANDBY POWER
A2
5 56Tuesday, January 20, 2015
Wiwynn Incorporated
http://www.wiwynn.com
8F, 90, Sec.1, Xintai 5th Rd., Xizhi Dist.,
New Taipei City 22102, Taiwan (R.O.C.)
Title 
Size Document Number Rev 
Date: Sheet o f 
Honey_Badger_uServer 1B
STANDBY POWER
A2
5 56Tuesday, January 20, 2015
Wiwynn Incorporated
http://www.wiwynn.com
8F, 90, Sec.1, Xintai 5th Rd., Xizhi Dist.,
New Taipei City 22102, Taiwan (R.O.C.)
Title 
Size Document Number Rev 
Date: Sheet o f 
Honey_Badger_uServer 1B
STANDBY POWER
A2
5 56Tuesday, January 20, 2015
Wiwynn Incorporated
http://www.wiwynn.com
8F, 90, Sec.1, Xintai 5th Rd., Xizhi Dist.,
New Taipei City 22102, Taiwan (R.O.C.)



5
5
4
4
3
3
2
2
1
1
D D
C C
B B
A A
4.7KΩ 
P12V 
G
S
D
S
G
D
SG
D
P3V3 
P3V3_STBY 
10KΩ 
P12V 
G
D
S
S
S
D
D
G
VDD 
P3V3_STBY 
P3V3_STBY 
G
P3V3_STBY 
VDD 
P12V 
P12V 
8.2kΩ 
PWRGD_P3V3_CPU_PG 
PWRGD_PVCCP/PVNN_PG 
MOS OUT 
IRFH4253 
P12V 
PMU_PWRBTN 
PWR BUTTON/BMC 
PMU_SLP_S45 
PMU_SLP_S3 
Switching (PU10) 
Ragurator (PU12) 
Ragurator (PU4) 
Switching (PU1) 
Switching (PU3) 
15KΩ 
P3V3_STBY 
VCC 
Y A
AY
GND 
P3V3_EN 
AND 
FPGA 
33Ω 
10kΩ 
P3V3_STBY 
4.02KΩ 
P12V 
10KΩ 
P3V3_STBY 
1u 
17.6kΩ 
P1V8_STBY 
2.2u 
P1V8 
10KΩ 
P3V3_STBY 
CLOCK_EN 
PLATFORM_RESET OTHER LOGIC 
 CIRCUIT CONTROL 
CLOCK GEN 
AUTO POWER ON 
PV_VDDR 
10KΩ 
P3V3 
10KΩ 
CPUCORE_PWROK 
0Ω 
PWRGD_P1V0_PG 
1KΩ 
P1V8 
CPU 
1KΩ 
P1V35 
P1V35_EN 
P1V0 
(OD) 
P1V0_EN OUT IN 
TPS53319DQPR-GP 
PGOOD EN 
P1V0_VREG 
10KΩ 
OUT IN 
TPS74801RGW-GP 
PGOOD EN (OD) 
PWRGD_P1V35_PG 
P1V8_STBY P3V3_STBY 
Switching (PU7) 
LDO (PU16) 10KΩ 
10KΩ 
P3V3_STBY PV_VTT_DDR_A 
PVTT_DDR_EN 
PV_VDDR 
(OD) 
OUT IN 
TPS51200-GP-U1 
PGOOD 
POWER_ON 
EN 
(OD) EN PGOOD 
ISL6353CRTZ-GP-U 
IN GATE 
PWRGD_PVDDR_PG 
P3V3_STBY 
ALL POWER_PG 
10KΩ 
PVCCP 
PVCC_PVNN_EN GATE IN 
EN 
ISL95831HRTZ-T-GP 
VDD 
DDR3_DRAM_PWROK 
P5V 
P3V3_STBY 
VDD 
PMU_SLP_DDRVTT 
PV_VTT_DDR_B 
VDD 
IN OUT 
(OD) 
PWRGD_PVTT_PG 
EN 
P3V3_STBY 
P3V3_STBY 
PGOOD 
TPS51200-GP-U1 
PV_VDDR 
PV_VDDR 
VDD P12V 
P1V1 
P5V 
P1V1_EN 
(OD) 
EN6337QI-GP-U PGOOD EN 
OUT IN 
Normal Power 
PVNN 
10KΩ 
FDMC8200 
IRFH4253 
MOS 
GATE 
OUT 
OUT 
MOS 
(OD) PGOOD 
P3V3_STBY 
1.91KΩ 
PVTT_DDR_EN 
Title 
Size Document Number Re v 
Date: Sheet 
o f 
Honey_Badger_uServer 1B
NORMAL POWER
Custom
6 56Tuesday, January 20, 2015
Wiwynn Incorporated
http://www.wiwynn.com
8F, 90, Sec.1, Xintai 5th Rd., Xizhi Dist.,
New Taipei City 22102, Taiwan (R.O.C.)
Title 
Size Document Number Re v 
Date: Sheet 
o f 
Honey_Badger_uServer 1B
NORMAL POWER
Custom
6 56Tuesday, January 20, 2015
Wiwynn Incorporated
http://www.wiwynn.com
8F, 90, Sec.1, Xintai 5th Rd., Xizhi Dist.,
New Taipei City 22102, Taiwan (R.O.C.)
Title 
Size Document Number Re v 
Date: Sheet 
o f 
Honey_Badger_uServer 1B
NORMAL POWER
Custom
6 56Tuesday, January 20, 2015
Wiwynn Incorporated
http://www.wiwynn.com
8F, 90, Sec.1, Xintai 5th Rd., Xizhi Dist.,
New Taipei City 22102, Taiwan (R.O.C.)



5
5
4
4
3
3
2
2
1
1
D D
C C
B B
A A
G3 S0 S3 
PWRGD_P12V_PG 
P3V3_CPU 
>10ms 
>60us 
S45 
>9ms 
P2V5_STBY 
>10ms 
<4S 
>100ms 
SYSTEM CLOCKS 
DRAMPWROK 
PMU_SUS_STAT# 
PMU_PLTRST# 
DDR3_X_VCCA_PWROK 
PV_VTT_DDR 
PV_VDDR 
P3V3 
P1V8 
P1V0 
P1V35 
PVCC 
PVNN 
P1V1 
PMU_SLP_S45# 
PMU_SLP_DDRVTT# 
PMU_SLP_S3# 
S3 
>30us 
>10ms 
>60us 
>30us 
<5ms 
S45 S3 S0 
SYSTEM CLOCKS 
DRAMPWROK 
P1V0_STBY 
P1V5_STBY 
P1V2_STBY 
P1V8_STBY 
32KHZ 
PMU_SUSCLK 
SUSPWRDNack 
PMU_SLP_S45# 
CPU_RSMRST# 
PMU_SUS_STAT# 
PMU_PLTRST# 
DDR3_X_VCCA_PWROK 
P12V 
POWER SEQUENCE DIAGRAM 
SRTCRST# 
PV_VTT_DDR 
PV_VDDR 
P3V3_STBY 
PMU_SLP_DDRVTT# 
PMU_SLP_S3# 
PWRBTN# 
P3V3 
P1V8 
P1V0 
P1V35 
PVCC 
PVNN 
P1V1 
Title 
Size Document Number R e v 
Date: Sheet 
o f 
Honey_Badger_uServer 1B
POWER SEQUENCE
A3
7 56Tuesday, January 20, 2015
Wiwynn Incorporated
http://www.wiwynn.com
8F, 90, Sec.1, Xintai 5th Rd., Xizhi Dist.,
New Taipei City 22102, Taiwan (R.O.C.)
Title 
Size Document Number R e v 
Date: Sheet 
o f 
Honey_Badger_uServer 1B
POWER SEQUENCE
A3
7 56Tuesday, January 20, 2015
Wiwynn Incorporated
http://www.wiwynn.com
8F, 90, Sec.1, Xintai 5th Rd., Xizhi Dist.,
New Taipei City 22102, Taiwan (R.O.C.)
Title 
Size Document Number R e v 
Date: Sheet 
o f 
Honey_Badger_uServer 1B
POWER SEQUENCE
A3
7 56Tuesday, January 20, 2015
Wiwynn Incorporated
http://www.wiwynn.com
8F, 90, Sec.1, Xintai 5th Rd., Xizhi Dist.,
New Taipei City 22102, Taiwan (R.O.C.)



5
5
4
4
3
3
2
2
1
1
D D
C C
B B
A A
4.7KΩ 
EEPROM 
M24128 
ADDR: 0xA2 
P3V3 
I2C_CLK/DATA0 
(M) 
SMB_CLK/DATA2(PECI) 
(S) 
SMB_CLK/DATA0 
(M) 
AVOTON 
ITP    XDP 
DIMM: Channel_B 
ADDR: 0xA4 & 0xA6 
CLOCK GEN 
9VRS4420 
ADDR: 0xD2 
TEMP SENSOR 
TMP75 
ADDR: 0x98 
FPGA 
SMB_PECI 
DIMM: Channel_A 
ADDR: 0xA0 & 0xA2 
DDR3 VREF TUNING 
ISL90727 
ADDR: 0x5C 
SMB_HOST 
I2C TOPOLOGY 
I2C_CLK/DATA1 
(S) 
BMC_I2C 
PCIE X16 4.7KΩ 
P3V3_STBY 
(M):Master 
(S):Slave 
4.7KΩ 
P3V3 
I2C_CLK/DATA2 
(M) 
4.7KΩ 
P3V3_STBY 
4.7KΩ 
P3V3_STBY CPU THERMAL 
SENSOR ADDRESS: 
0x96,0x98 
VOLTAGE SENSOR 
ADS7828 
ADDR: 0x92 
GPO 
SMBUS_SW_EN 
CLOCK BUFFER 
9DB833 
ADDR:0xD8 
GPO 
BIOS_POST_COMPLETE# 
S
IN1 
IN2 
OUT 
4.7KΩ 
P3V3_STBY 
S
IN1 =  OUT 
IN2 =  OUT 
H
L
FUNCTION 
Switch IC 
I2C to SPI switch 
SC18IS602B 
ADDR: 0x50 
SMBUS_SW_EN 
Title 
Size Document Number R e v 
Date: Sheet 
o f 
Honey_Badger_uServer 1B
I2C TOPOLOGY
A3
8 56Tuesday, January 20, 2015
Wiwynn Incorporated
http://www.wiwynn.com
8F, 90, Sec.1, Xintai 5th Rd., Xizhi Dist.,
New Taipei City 22102, Taiwan (R.O.C.)
Title 
Size Document Number R e v 
Date: Sheet 
o f 
Honey_Badger_uServer 1B
I2C TOPOLOGY
A3
8 56Tuesday, January 20, 2015
Wiwynn Incorporated
http://www.wiwynn.com
8F, 90, Sec.1, Xintai 5th Rd., Xizhi Dist.,
New Taipei City 22102, Taiwan (R.O.C.)
Title 
Size Document Number R e v 
Date: Sheet 
o f 
Honey_Badger_uServer 1B
I2C TOPOLOGY
A3
8 56Tuesday, January 20, 2015
Wiwynn Incorporated
http://www.wiwynn.com
8F, 90, Sec.1, Xintai 5th Rd., Xizhi Dist.,
New Taipei City 22102, Taiwan (R.O.C.)



5
5
4
4
3
3
2
2
1
1
D D
C C
B B
A A
100MHz_DDR3_CH0 
100MHz_CPU 
100MHz_SATA3 
96MHz_USB 
XTAL 
ETHER 10G Controller 
32.768KHz 
DDR3_CLK[3:0] 
100MHz_PCIE 
DIMM 
SRC4_LRS 
SRC3_LRS 
NGFF 100MHz_NGFF 
HPLL 
14.31818MHz 
OSC 
SRC5_LRS 
DDR3_CH1 
SATA3 
GbE 
USB 
DIFF1_LRS 
DIFF0_LRS 
SATA 
DOT96/SRC6 
REF 
100MHz_DDR3_CH1 
100MHz_GbE 
9DB833 
DIFF0 
DIFF1 
DIFF2 
SRC_IN 
DIFF3 
OE_0# 
OE_1# 
OE_2# 
OE_3# 
100MHz_10G 
100MHz_XDP 
FPGA 
Avoton CPU 
DDR3_CH0 
PCIE 
CLK_5MHz 
SRC1_LRS 
9VRS4420 
SRC2_LRS 
1600MHz_DDR 
14MHz_REF 
CPU XDP 
SPI_CLK 
SVID_CLK SVIDVR 
FLASH 
CLK14_IN 
SAS I/O controller 100MHz_SAS Storage 
100MHz_SATA2 SATA2 
OE_4# 
TBD 100MHz_PCIE2 REFCLK 
DIFF4 
Title 
Size Document Number R e v 
Date: Sheet 
o f 
Honey_Badger_uServer 1B
CLOCK DIAGRAM
A3
9 56Tuesday, January 20, 2015
Wiwynn Incorporated
http://www.wiwynn.com
8F, 90, Sec.1, Xintai 5th Rd., Xizhi Dist.,
New Taipei City 22102, Taiwan (R.O.C.)
Title 
Size Document Number R e v 
Date: Sheet 
o f 
Honey_Badger_uServer 1B
CLOCK DIAGRAM
A3
9 56Tuesday, January 20, 2015
Wiwynn Incorporated
http://www.wiwynn.com
8F, 90, Sec.1, Xintai 5th Rd., Xizhi Dist.,
New Taipei City 22102, Taiwan (R.O.C.)
Title 
Size Document Number R e v 
Date: Sheet 
o f 
Honey_Badger_uServer 1B
CLOCK DIAGRAM
A3
9 56Tuesday, January 20, 2015
Wiwynn Incorporated
http://www.wiwynn.com
8F, 90, Sec.1, Xintai 5th Rd., Xizhi Dist.,
New Taipei City 22102, Taiwan (R.O.C.)



5
5
4
4
3
3
2
2
1
1
D D
C C
B B
A A
BLANK 
Title 
Size Document Number R e v 
Date: Sheet 
o f 
Honey_Badger_uServer 1B
BLANK
A3
10 56Tuesday, January 20, 2015
Wiwynn Incorporated
http://www.wiwynn.com
8F, 90, Sec.1, Xintai 5th Rd., Xizhi Dist.,
New Taipei City 22102, Taiwan (R.O.C.)
Title 
Size Document Number R e v 
Date: Sheet 
o f 
Honey_Badger_uServer 1B
BLANK
A3
10 56Tuesday, January 20, 2015
Wiwynn Incorporated
http://www.wiwynn.com
8F, 90, Sec.1, Xintai 5th Rd., Xizhi Dist.,
New Taipei City 22102, Taiwan (R.O.C.)
Title 
Size Document Number R e v 
Date: Sheet 
o f 
Honey_Badger_uServer 1B
BLANK
A3
10 56Tuesday, January 20, 2015
Wiwynn Incorporated
http://www.wiwynn.com
8F, 90, Sec.1, Xintai 5th Rd., Xizhi Dist.,
New Taipei City 22102, Taiwan (R.O.C.)



5
5
4
4
3
3
2
2
1
1
D D
C C
B B
A A
M_A_DQ0
M_A_DQS_DP0
M_A_DQS_DN0
M_A_MA0
M_A_ECC0
M_A_CK_DP0
M_A_CKE0
M_A_CS_N0
M_A_ODT0
M_A_BS0
M_A_MON2_N
M_A_MON2_P
M_A_MON1_N
M_A_MON1_P
M_A_CMDPU
M_A_DQPU
M_A_DQS_DN8
M_A_DQS_DP8
M_A_ODTPU
M_A_WE#
M_A_RAS#
M_A_CAS#
M_DRAM_PWROK
M_A_VREF
M_A_CMDPU
M_A_DQPU
M_A_ODTPU
M_A_MON1_P
M_A_MON1_N
M_A_MON2_P
M_A_MON2_N
M_A_DQ1
M_A_DQ2
M_A_DQ3
M_A_DQ4
M_A_DQ5
M_A_DQ6
M_A_DQ7
M_A_DQ8
M_A_DQ9
M_A_DQ10
M_A_DQ11
M_A_DQ12
M_A_DQ13
M_A_DQ14
M_A_DQ15
M_A_DQ16
M_A_DQ17
M_A_DQ18
M_A_DQ19
M_A_DQ20
M_A_DQ21
M_A_DQ22
M_A_DQ23
M_A_DQ24
M_A_DQ25
M_A_DQ26
M_A_DQ27
M_A_DQ28
M_A_DQ29
M_A_DQ30
M_A_DQ31
M_A_DQ32
M_A_DQ33
M_A_DQ34
M_A_DQ35
M_A_DQ36
M_A_DQ37
M_A_DQ38
M_A_DQ39
M_A_DQ40
M_A_DQ41
M_A_DQ42
M_A_DQ43
M_A_DQ44
M_A_DQ45
M_A_DQ46
M_A_DQ47
M_A_DQ48
M_A_DQ49
M_A_DQ50
M_A_DQ51
M_A_DQ52
M_A_DQ53
M_A_DQ54
M_A_DQ55
M_A_DQ56
M_A_DQ57
M_A_DQ58
M_A_DQ59
M_A_DQ60
M_A_DQ61
M_A_DQ62
M_A_DQ63
M_A_DQS_DP1
M_A_DQS_DP2
M_A_DQS_DP3
M_A_DQS_DP4
M_A_DQS_DP5
M_A_DQS_DP6
M_A_DQS_DP7
M_A_DQS_DN1
M_A_DQS_DN2
M_A_DQS_DN3
M_A_DQS_DN4
M_A_DQS_DN5
M_A_DQS_DN6
M_A_DQS_DN7
M_A_MA1
M_A_MA2
M_A_MA3
M_A_MA4
M_A_MA5
M_A_MA6
M_A_MA7
M_A_MA8
M_A_MA9
M_A_MA10
M_A_MA11
M_A_MA12
M_A_MA13
M_A_MA14
M_A_MA15
M_A_ECC1
M_A_ECC2
M_A_ECC3
M_A_ECC4
M_A_ECC5
M_A_ECC6
M_A_ECC7
M_A_CK_DP1
M_A_CK_DN0
M_A_CK_DN1
M_A_CS_N1
M_A_CKE1
M_A_ODT1
M_A_BS1
M_A_BS2
M_A_VREF
M_DRAM_PWROK
M_A_R_RESET#
PWRGD_DDR3_VCCA
M_A_CK_DP3
M_A_CK_DP2
M_A_CK_DN2
M_A_CK_DN3
M_A_CKE3
M_A_CKE2
M_A_CS_N3
M_A_CS_N2
M_A_ODT3
M_A_ODT2
PV_VDDR
PV_VDDR
M_A_CK_DP0 26
M_A_CKE0 26
M_A_MA[15:0] 26,27
M_A_ECC[7:0] 26,27
M_A_DQ[63:0]26,27
M_A_CS_N0 26
M_A_DQS_DP026,27
M_A_DQS_DN026,27
M_A_ODT0 26
M_A_BS0 26,27
M_A_WE# 26,27
M_A_RAS# 26,27
M_A_CAS# 26,27
M_A_DQS_DN8 26,27
M_A_DQS_DP8 26,27
CLK_100M_CPU_MPLL0_DP 31
CLK_100M_CPU_MPLL0_DN 31
M_DRAM_PWROK 12,22
PWRGD_DDR3_VCCA 12,22
M_A_DQS_DP126,27
M_A_DQS_DP226,27
M_A_DQS_DP326,27
M_A_DQS_DP426,27
M_A_DQS_DP526,27
M_A_DQS_DP626,27
M_A_DQS_DP726,27
M_A_DQS_DN126,27
M_A_DQS_DN226,27
M_A_DQS_DN326,27
M_A_DQS_DN426,27
M_A_DQS_DN526,27
M_A_DQS_DN626,27
M_A_DQS_DN726,27
M_A_CK_DP1 26
M_A_CK_DN0 26
M_A_CK_DN1 26
M_A_CS_N1 26
M_A_CKE1 26
M_A_ODT1 26
M_A_BS1 26,27
M_A_BS2 26,27
M_A_RESET# 26,27
M_A_CK_DP2 27
M_A_CK_DP3 27
M_A_CK_DN2 27
M_A_CK_DN3 27
M_A_CKE2 27
M_A_CKE3 27
M_A_CS_N2 27
M_A_CS_N3 27
M_A_ODT2 27
M_A_ODT3 27
Title 
Size Document Number R e v 
Date: Sheet 
o f 
Honey_Badger_uServer 1B
CPU DDR CHA
A3
11 56Tuesday, January 20, 2015
Wiwynn Incorporated
http://www.wiwynn.com
8F, 90, Sec.1, Xintai 5th Rd., Xizhi Dist.,
New Taipei City 22102, Taiwan (R.O.C.)
Title 
Size Document Number R e v 
Date: Sheet 
o f 
Honey_Badger_uServer 1B
CPU DDR CHA
A3
11 56Tuesday, January 20, 2015
Wiwynn Incorporated
http://www.wiwynn.com
8F, 90, Sec.1, Xintai 5th Rd., Xizhi Dist.,
New Taipei City 22102, Taiwan (R.O.C.)
Title 
Size Document Number R e v 
Date: Sheet 
o f 
Honey_Badger_uServer 1B
CPU DDR CHA
A3
11 56Tuesday, January 20, 2015
Wiwynn Incorporated
http://www.wiwynn.com
8F, 90, Sec.1, Xintai 5th Rd., Xizhi Dist.,
New Taipei City 22102, Taiwan (R.O.C.)
R24
100R2F-L1-GP-U
1 2
R281
100R2F-L1-GP-U
1 2
R279
23D7R2F-GP
1 2
R303
162R2F-GP
1 2
R21
100R3F-1-GP
NOPOP
1 2
R287
100R2F-L1-GP-U
NOPOP
1 2
R258
1KR2F-3-GP
NOPOP
1 2
C125
SCD1U16V2KX-L-GP
NOPOP
1 2
R22
100R3F-1-GP
NOPOP
1 2
R285
0R2J-2-GP
NOPOP
1 2
R261
100KR2F-L1-GP
12
R309
30D1R2F-L-GP
1 2
R2590R2J-2-GP 12
C141
SC33P50V2JN-3GP
NOPOP
1 2
AVOTON 
1 OF 12 U13A
AVOTON-GP
DDR3_0_WE# BC23
DDR3_0_VREF AY29
DDR3_0_VCCA_PWROK BE17
DDR3_0_REFP BN12
DDR3_0_REFN BM13
DDR3_0_RAS# BG23
DDR3_0_ODTPU AW20
DDR3_0_ODT0 BD26DDR3_0_ODT1 BB26DDR3_0_ODT2 BH25DDR3_0_ODT3 BG25
DDR3_0_MON2P BK5
DDR3_0_MON2N BK3
DDR3_0_MON1P BP8
DDR3_0_MON1N BP6
DDR3_0_MA0 BH11DDR3_0_MA1 BL8DDR3_0_MA2 BG13DDR3_0_MA3 BG11DDR3_0_MA4 BD13DDR3_0_MA5 BM7DDR3_0_MA6 BD10DDR3_0_MA7 BH8DDR3_0_MA8 BD8DDR3_0_MA9 BD15DDR3_0_MA10 BN10DDR3_0_MA11 BG8DDR3_0_MA12 BD7DDR3_0_MA13 BA23DDR3_0_MA14 BC11DDR3_0_MA15 BF15
DDR3_0_DRAM_PWROK BG17
DDR3_0_DRAMRST# BA25
DDR3_0_DQS0#AL12 DDR3_0_DQS1#AR7 DDR3_0_DQS2#AW11 DDR3_0_DQS3#AP1 DDR3_0_DQS4#BC29 DDR3_0_DQS5#BN17 DDR3_0_DQS6#BL26 DDR3_0_DQS7#BM34
DDR3_0_DQSECC0 BB2DDR3_0_DQSBECC0 BB4
DDR3_0_DQS0AL11 DDR3_0_DQS1AT7 DDR3_0_DQS2AW12 DDR3_0_DQS3AP3 DDR3_0_DQS4BD29 DDR3_0_DQS5BM18 DDR3_0_DQS6BN26 DDR3_0_DQS7BP34
DDR3_0_DQPU AW21
DDR3_0_DQECC0 AY4DDR3_0_DQECC1 AY2DDR3_0_DQECC2 BD2DDR3_0_DQECC3 BD4DDR3_0_DQECC4 AW3DDR3_0_DQECC5 AY1DDR3_0_DQECC6 BC1DDR3_0_DQECC7 BC3
DDR3_0_DQ0AM15 DDR3_0_DQ1AM14 DDR3_0_DQ2AL8 DDR3_0_DQ3AM8 DDR3_0_DQ4AM17 DDR3_0_DQ5AL15 DDR3_0_DQ6AM11 DDR3_0_DQ7AM9 DDR3_0_DQ8AR14 DDR3_0_DQ9AT13 DDR3_0_DQ10AT10 DDR3_0_DQ11AR11 DDR3_0_DQ12AR16 DDR3_0_DQ13AT14 DDR3_0_DQ14AT8 DDR3_0_DQ15AR10 DDR3_0_DQ16AY9 DDR3_0_DQ17AY11 DDR3_0_DQ18AY15 DDR3_0_DQ19AW17 DDR3_0_DQ20AW8 DDR3_0_DQ21AY8 DDR3_0_DQ22AY14 DDR3_0_DQ23AW15 DDR3_0_DQ24AN4 DDR3_0_DQ25AN2 DDR3_0_DQ26AU1 DDR3_0_DQ27AU3 DDR3_0_DQ28AL2 DDR3_0_DQ29AL4 DDR3_0_DQ30AR2 DDR3_0_DQ31AR4 DDR3_0_DQ32BA32 DDR3_0_DQ33BA30
DDR3_0_DQ39BG30 DDR3_0_DQ40BL16 DDR3_0_DQ41BL17 DDR3_0_DQ42BL21 DDR3_0_DQ43BN21 DDR3_0_DQ44BM16 DDR3_0_DQ45BP16 DDR3_0_DQ46BP19 DDR3_0_DQ47BN19 DDR3_0_DQ48BM25 DDR3_0_DQ49BP25 DDR3_0_DQ50BL28 DDR3_0_DQ51BN28 DDR3_0_DQ52BL23 DDR3_0_DQ53BN23 DDR3_0_DQ54BM27 DDR3_0_DQ55BP28 DDR3_0_DQ56BN32 DDR3_0_DQ57BK32 DDR3_0_DQ58BN35 DDR3_0_DQ59BM36 DDR3_0_DQ60BM31 DDR3_0_DQ61BL32 DDR3_0_DQ62BK35 DDR3_0_DQ63BL35
DDR3_0_CS0# BE25DDR3_0_CS1# BB25DDR3_0_CS2# BD23DDR3_0_CS3# BG26
DDR3_0_CMDPU BA26
DDR3_0_CK0# BC21DDR3_0_CK1# BG21DDR3_0_CK2# BH19DDR3_0_CK3# BD19
DDR3_0_CKE0 BG4DDR3_0_CKE1 BH5DDR3_0_CKE2 BG5DDR3_0_CKE3 BH3
DDR3_0_CK0 BA21DDR3_0_CK1 BF21DDR3_0_CK2 BG19DDR3_0_CK3 BB19
DDR3_0_CAS# BH26
DDR3_0_BS0 BL12DDR3_0_BS1 BL10DDR3_0_BS2 BC8
DDR3_0_DQ34BF30 DDR3_0_DQ35BD30 DDR3_0_DQ36BB32 DDR3_0_DQ37AY30 DDR3_0_DQ38BG29
R23
100R2F-L1-GP-U
1 2



5
5
4
4
3
3
2
2
1
1
D D
C C
B B
A A
M_B_DQS_DP0
M_B_DQS_DN0
M_B_DQ0
M_B_DQS_DP1
M_B_DQS_DN1
M_B_DQS_DP2
M_B_DQS_DN2
M_B_DQS_DP3
M_B_DQS_DN3
M_B_DQS_DP4
M_B_DQS_DN4
M_B_DQS_DP5
M_B_DQS_DN5
M_B_DQS_DP6
M_B_DQS_DN6
M_B_DQS_DP7
M_B_DQS_DN7
M_B_DQ16
M_B_DQ32
M_B_DQ48
M_B_DQ1
M_B_DQ17
M_B_DQ33
M_B_DQ49
M_B_DQ2
M_B_DQ18
M_B_DQ34
M_B_DQ50
M_B_DQ3
M_B_DQ19
M_B_DQ35
M_B_DQ51
M_B_DQ4
M_B_DQ20
M_B_DQ36
M_B_DQ52
M_B_DQ5
M_B_DQ21
M_B_DQ37
M_B_DQ53
M_B_DQ6
M_B_DQ22
M_B_DQ38
M_B_DQ54
M_B_DQ7
M_B_DQ23
M_B_DQ39
M_B_DQ55
M_B_DQ8
M_B_DQ24
M_B_DQ40
M_B_DQ56
M_B_DQ9
M_B_DQ25
M_B_DQ41
M_B_DQ57
M_B_DQ10
M_B_DQ26
M_B_DQ42
M_B_DQ58
M_B_DQ11
M_B_DQ27
M_B_DQ43
M_B_DQ59
M_B_DQ12
M_B_DQ28
M_B_DQ44
M_B_DQ60
M_B_DQ13
M_B_DQ29
M_B_DQ45
M_B_DQ61
M_B_DQ14
M_B_DQ30
M_B_DQ46
M_B_DQ62
M_B_DQ15
M_B_DQ31
M_B_DQ47
M_B_DQ63
M_B_MON1_P
M_B_VREF
M_B_CMDPU
M_B_DQPU
M_B_MON1_N
M_B_ODTPU
M_DRAM_PWROK
M_B_MON2_P
M_B_MON2_N
M_B_MON2_N
M_B_MA0
M_B_CK_DP0
M_B_CK_DN0
M_B_MON2_P
M_DRAM_PWROK
M_B_WE#
M_B_MON1_N
M_B_MON1_P
M_B_ODT0
M_B_CMDPU
M_B_CKE0
M_B_RAS#
M_B_DQPU
M_B_CAS#
M_B_VREF
M_B_DQS_DN8
M_B_DQS_DP8
M_B_ECC0
M_B_ODTPU
M_B_BS0
M_B_CS_N0
M_B_MA8
M_B_MA9
M_B_MA1
M_B_ECC1
M_B_MA10
M_B_MA2
M_B_ECC2
M_B_MA11
M_B_MA3
M_B_ECC3
M_B_MA12
M_B_MA4
M_B_ECC4
M_B_MA13
M_B_MA5
M_B_ECC5
M_B_MA14
M_B_MA6
M_B_ECC6
M_B_MA15
M_B_MA7
M_B_ECC7
M_B_CK_DP1
M_B_CK_DN1
M_B_ODT1
M_B_CKE1
M_B_CS_N1
M_B_BS1
M_B_BS2
PWRGD_DDR3_VCCA
M_B_CK_DP3
M_B_CK_DP2
M_B_CK_DN3
M_B_CK_DN2
M_B_CKE3
M_B_CKE2
M_B_CS_N3
M_B_CS_N2
M_B_ODT3
M_B_ODT2
M_B_R_RESET#
PV_VDDR
PV_VDDR
M_B_DQS_DN028,29
M_B_DQ[63:0]28,29
M_B_DQS_DP028,29
M_B_DQS_DN128,29
M_B_DQS_DP128,29
M_B_DQS_DN228,29
M_B_DQS_DP228,29
M_B_DQS_DN328,29
M_B_DQS_DP328,29
M_B_DQS_DP428,29
M_B_DQS_DN428,29
M_B_DQS_DN528,29
M_B_DQS_DP528,29
M_B_DQS_DN628,29
M_B_DQS_DP628,29
M_B_DQS_DP728,29
M_B_DQS_DN728,29
M_B_CK_DP0 28
M_B_CKE0 28
M_B_DQS_DN8 28,29
M_B_DQS_DP8 28,29
M_B_ECC[7:0] 28,29
CLK_100M_CPU_MPLL1_DP 31
CLK_100M_CPU_MPLL1_DN 31
M_B_CK_DN0 28
M_DRAM_PWROK 11,22
M_B_WE# 28,29
M_B_RESET# 28,29
PWRGD_DDR3_VCCA 11,22
M_B_ODT0 28
M_B_MA[15:0] 28,29
M_B_RAS# 28,29
M_B_CAS# 28,29
M_B_BS0 28,29
M_B_CS_N0 28
M_B_CK_DP1 28
M_B_CKE1 28
M_B_CK_DN1 28
M_B_ODT1 28
M_B_CS_N1 28
M_B_BS1 28,29
M_B_BS2 28,29
M_B_CK_DP2 29
M_B_CK_DP3 29
M_B_CK_DN2 29
M_B_CK_DN3 29
M_B_CKE2 29
M_B_CKE3 29
M_B_CS_N2 29
M_B_CS_N3 29
M_B_ODT2 29
M_B_ODT3 29
Title 
Size Document Number R e v 
Date: Sheet 
o f 
Honey_Badger_uServer 1B
CPU DDR CHB
A3
12 56Tuesday, January 20, 2015
Wiwynn Incorporated
http://www.wiwynn.com
8F, 90, Sec.1, Xintai 5th Rd., Xizhi Dist.,
New Taipei City 22102, Taiwan (R.O.C.)
Title 
Size Document Number R e v 
Date: Sheet 
o f 
Honey_Badger_uServer 1B
CPU DDR CHB
A3
12 56Tuesday, January 20, 2015
Wiwynn Incorporated
http://www.wiwynn.com
8F, 90, Sec.1, Xintai 5th Rd., Xizhi Dist.,
New Taipei City 22102, Taiwan (R.O.C.)
Title 
Size Document Number R e v 
Date: Sheet 
o f 
Honey_Badger_uServer 1B
CPU DDR CHB
A3
12 56Tuesday, January 20, 2015
Wiwynn Incorporated
http://www.wiwynn.com
8F, 90, Sec.1, Xintai 5th Rd., Xizhi Dist.,
New Taipei City 22102, Taiwan (R.O.C.)
R160
100R2F-L1-GP-U
1 2
AVOTON 
2 OF 12 U13B
AVOTON-GP
DDR3_1_BS2 H25
DDR3_1_BS1 H18
DDR3_1_BS0 N18
DDR3_1_CAS# H4
DDR3_1_CK3 J13
DDR3_1_CK2 H10
DDR3_1_CK1 G9
DDR3_1_CK0 C9
DDR3_1_CKE3 L26
DDR3_1_CKE2 L25
DDR3_1_CKE1 N25
DDR3_1_CKE0 N26
DDR3_1_CK3# L13
DDR3_1_CK2# G10
DDR3_1_CK1# H9
DDR3_1_CK0# D8
DDR3_1_CMDPU T25
DDR3_1_CS3# K4
DDR3_1_CS2# L7
DDR3_1_CS1# N4
DDR3_1_CS0# K3
DDR3_1_DQ63AC15
DDR3_1_DQ62AC14
DDR3_1_DQ61AC9
DDR3_1_DQ60AC11
DDR3_1_DQ59AC17
DDR3_1_DQ58AD15
DDR3_1_DQ57AD8
DDR3_1_DQ56AC8
DDR3_1_DQ55Y10
DDR3_1_DQ54W8
DDR3_1_DQ53Y14
DDR3_1_DQ52Y16
DDR3_1_DQ51Y11
DDR3_1_DQ50W10
DDR3_1_DQ49W13
DDR3_1_DQ48W14
DDR3_1_DQ47Y2
DDR3_1_DQ46Y4
DDR3_1_DQ45T1
DDR3_1_DQ44T3
DDR3_1_DQ43AB4
DDR3_1_DQ42AB2
DDR3_1_DQ41U2
DDR3_1_DQ40U4
DDR3_1_DQ39U8
DDR3_1_DQ38R8
DDR3_1_DQ37U15
DDR3_1_DQ36T17
DDR3_1_DQ35R11
DDR3_1_DQ34R9
DDR3_1_DQ33R14
DDR3_1_DQ32R15
DDR3_1_DQ31P30
DDR3_1_DQ30M30
DDR3_1_DQ29J30
DDR3_1_DQ28H32
DDR3_1_DQ27L32
DDR3_1_DQ26N32
DDR3_1_DQ25H29
DDR3_1_DQ24H30
DDR3_1_DQ23D21
DDR3_1_DQ22B21
DDR3_1_DQ21D24
DDR3_1_DQ20C24
DDR3_1_DQ19B19
DDR3_1_DQ18D19
DDR3_1_DQ17B23
DDR3_1_DQ16D23
DDR3_1_DQ15B28
DDR3_1_DQ14D28
DDR3_1_DQ13D32
DDR3_1_DQ12E32
DDR3_1_DQ11C27
DDR3_1_DQ10A27
DDR3_1_DQ9C31
DDR3_1_DQ8B32
DDR3_1_DQ7C36
DDR3_1_DQ6A36
DDR3_1_DQ5C40
DDR3_1_DQ4A39
DDR3_1_DQ3D35
DDR3_1_DQ2B35
DDR3_1_DQ1D39
DDR3_1_DQ0B39
DDR3_1_DQECC7 B12
DDR3_1_DQECC6 C13
DDR3_1_DQECC5 B17
DDR3_1_DQECC4 D17
DDR3_1_DQECC3 E12
DDR3_1_DQECC2 D12
DDR3_1_DQECC1 C15
DDR3_1_DQECC0 D15
DDR3_1_DQPU T26
DDR3_1_DQS7AD12
DDR3_1_DQS6Y7
DDR3_1_DQS5W1
DDR3_1_DQS4U11
DDR3_1_DQS3M29
DDR3_1_DQS2A21
DDR3_1_DQS1D30
DDR3_1_DQS0D37
DDR3_1_DQSBECC0 D14
DDR3_1_DQSECC0 B14
DDR3_1_DQS7#AD11
DDR3_1_DQS6#W7
DDR3_1_DQS5#W3
DDR3_1_DQS4#U12
DDR3_1_DQS3#L29
DDR3_1_DQS2#C22
DDR3_1_DQS1#B30
DDR3_1_DQS0#B37
DDR3_1_DRAMRST# N11
DDR3_1_DRAM_PWROK L17
DDR3_1_MA15 H26
DDR3_1_MA14 G26
DDR3_1_MA13 G3
DDR3_1_MA12 G25
DDR3_1_MA11 P22
DDR3_1_MA10 L18
DDR3_1_MA9 M22
DDR3_1_MA8 H21
DDR3_1_MA7 J22
DDR3_1_MA6 J21
DDR3_1_MA5 H22
DDR3_1_MA4 M21
DDR3_1_MA3 P21
DDR3_1_MA2 G18
DDR3_1_MA1 G17
DDR3_1_MA0 H17
DDR3_1_MON1N C5DDR3_1_MON1P E5
DDR3_1_MON2N A6DDR3_1_MON2P A8
DDR3_1_ODT3 L4
DDR3_1_ODT2 N8
DDR3_1_ODT1 N2
DDR3_1_ODT0 L2
DDR3_1_ODTPU T32
DDR3_1_RAS# L8
DDR3_1_REFN L14DDR3_1_REFP J14
DDR3_1_VCCA_PWROK N17
DDR3_1_VREF R29
DDR3_1_WE# N7
R162
100KR2F-L1-GP
12
R353
0R2J-2-GP
NOPOP
1 2
R380
23D7R2F-GP
1 2
R350
162R2F-GP
1 2
R373
100R2F-L1-GP-U
NOPOP
1 2
R374
100R2F-L1-GP-U
1 2
R170
1KR2F-3-GP
NOPOP
1 2
R161
100R2F-L1-GP-U
1 2
R1650R2J-2-GP 12
R167
100R3F-1-GP
NOPOP
1 2
R168
100R3F-1-GP
NOPOP
1 2
C244
SCD1U16V2KX-L-GP
NOPOP
1 2
R381
30D1R2F-L-GP
1 2
C222
SC33P50V2JN-3GP
NOPOP
1 2



5
5
4
4
3
3
2
2
1
1
D D
C C
B B
A A
PCIE_OBS_N
PCIE_OBS_P
PCIE_OBS_N
PCIE_OBS_P
P2E_CPU_NGFF_RX_DN12
P2E_CPU_NGFF_RX_DP12
P2E_CPU_ETH10G_RX_DN8
P2E_CPU_ETH10G_RX_DP8
P2E_CPU_SAS_RX_DP0
P2E_CPU_SAS_RX_DN0
P2E_CPU_SAS_RX_DN1
P2E_CPU_SAS_RX_DP1
P2E_CPU_SAS_RX_DN2
P2E_CPU_SAS_RX_DP2
P2E_CPU_SAS_RX_DN3
P2E_CPU_SAS_RX_DP3
P2E_CPU_SAS_RX_DN4
P2E_CPU_SAS_RX_DP4
P2E_CPU_SAS_RX_DN5
P2E_CPU_SAS_RX_DP5
P2E_CPU_SAS_RX_DN6
P2E_CPU_SAS_RX_DP6
P2E_CPU_SAS_RX_DN7
P2E_CPU_SAS_RX_DP7
P2E_CPU_ETH10G_RX_DN9
P2E_CPU_ETH10G_RX_DP9
P2E_CPU_ETH10G_RX_DN10
P2E_CPU_ETH10G_RX_DP10
P2E_CPU_ETH10G_RX_DN11
P2E_CPU_ETH10G_RX_DP11
P2E_CPU_ETH10G_C_TX_DP8
P2E_CPU_ETH10G_C_TX_DN8
P2E_CPU_NGFF_C_TX_DP12
P2E_CPU_NGFF_C_TX_DN12
P2E_CPU_SAS_C_TX_DN0
P2E_CPU_SAS_C_TX_DP0
P2E_CPU_SAS_C_TX_DP1
P2E_CPU_SAS_C_TX_DN1
P2E_CPU_SAS_C_TX_DP2
P2E_CPU_SAS_C_TX_DN2
P2E_CPU_SAS_C_TX_DP3
P2E_CPU_SAS_C_TX_DN3
P2E_CPU_SAS_C_TX_DP4
P2E_CPU_SAS_C_TX_DN4
P2E_CPU_SAS_C_TX_DP5
P2E_CPU_SAS_C_TX_DN5
P2E_CPU_SAS_C_TX_DP6
P2E_CPU_SAS_C_TX_DN6
P2E_CPU_SAS_C_TX_DP7
P2E_CPU_SAS_C_TX_DN7
P2E_CPU_ETH10G_C_TX_DN9
P2E_CPU_ETH10G_C_TX_DP9
P2E_CPU_ETH10G_C_TX_DP10
P2E_CPU_ETH10G_C_TX_DN10
P2E_CPU_ETH10G_C_TX_DP11
P2E_CPU_ETH10G_C_TX_DN11
P2E_CPU_NGFF_C_TX_DN13
P2E_CPU_NGFF_C_TX_DP13
P2E_CPU_NGFF_C_TX_DP14
P2E_CPU_NGFF_C_TX_DN14
P2E_CPU_NGFF_C_TX_DP15
P2E_CPU_NGFF_C_TX_DN15
P2E_CPU_NGFF_RX_DN13
P2E_CPU_NGFF_RX_DP13
P2E_CPU_NGFF_RX_DN14
P2E_CPU_NGFF_RX_DP14
P2E_CPU_NGFF_RX_DN15
P2E_CPU_NGFF_RX_DP15
CLK_100M_CLKBUFF_PCIE_DP 32
CLK_100M_CLKBUFF_PCIE_DN 32
P2E_CPU_NGFF_RX_DP1234
P2E_CPU_NGFF_RX_DN1234
P2E_CPU_ETH10G_RX_DP837
P2E_CPU_ETH10G_RX_DN837
P2E_CPU_SAS_RX_DN037
P2E_CPU_SAS_RX_DP037
P2E_CPU_SAS_RX_DP137
P2E_CPU_SAS_RX_DN137
P2E_CPU_SAS_RX_DP237
P2E_CPU_SAS_RX_DN237
P2E_CPU_SAS_RX_DN337
P2E_CPU_SAS_RX_DP337
P2E_CPU_SAS_RX_DP437
P2E_CPU_SAS_RX_DN437
P2E_CPU_SAS_RX_DN537
P2E_CPU_SAS_RX_DP537
P2E_CPU_SAS_RX_DN637
P2E_CPU_SAS_RX_DP637
P2E_CPU_SAS_RX_DP737
P2E_CPU_SAS_RX_DN737
P2E_CPU_ETH10G_RX_DN937
P2E_CPU_ETH10G_RX_DP937
P2E_CPU_ETH10G_RX_DP1037
P2E_CPU_ETH10G_RX_DN1037
P2E_CPU_ETH10G_RX_DN1137
P2E_CPU_ETH10G_RX_DP1137
P2E_CPU_NGFF_C_TX_DP12 34
P2E_CPU_NGFF_C_TX_DN12 34
P2E_CPU_ETH10G_C_TX_DP8 37
P2E_CPU_ETH10G_C_TX_DN8 37
P2E_CPU_SAS_C_TX_DP0 37
P2E_CPU_SAS_C_TX_DN0 37
P2E_CPU_SAS_C_TX_DN1 37
P2E_CPU_SAS_C_TX_DP1 37
P2E_CPU_SAS_C_TX_DN2 37
P2E_CPU_SAS_C_TX_DP2 37
P2E_CPU_SAS_C_TX_DP3 37
P2E_CPU_SAS_C_TX_DN3 37
P2E_CPU_SAS_C_TX_DN4 37
P2E_CPU_SAS_C_TX_DP4 37
P2E_CPU_SAS_C_TX_DP5 37
P2E_CPU_SAS_C_TX_DN5 37
P2E_CPU_SAS_C_TX_DP6 37
P2E_CPU_SAS_C_TX_DN6 37
P2E_CPU_SAS_C_TX_DP7 37
P2E_CPU_SAS_C_TX_DN7 37
P2E_CPU_ETH10G_C_TX_DN9 37
P2E_CPU_ETH10G_C_TX_DP9 37
P2E_CPU_ETH10G_C_TX_DP10 37
P2E_CPU_ETH10G_C_TX_DN10 37
P2E_CPU_ETH10G_C_TX_DN11 37
P2E_CPU_ETH10G_C_TX_DP11 37
P2E_CPU_NGFF_C_TX_DN13 34
P2E_CPU_NGFF_C_TX_DP13 34
P2E_CPU_NGFF_C_TX_DP14 34
P2E_CPU_NGFF_C_TX_DN14 34
P2E_CPU_NGFF_C_TX_DP15 34
P2E_CPU_NGFF_C_TX_DN15 34
P2E_CPU_NGFF_RX_DP1334
P2E_CPU_NGFF_RX_DN1334
P2E_CPU_NGFF_RX_DN1434
P2E_CPU_NGFF_RX_DP1434
P2E_CPU_NGFF_RX_DP1534
P2E_CPU_NGFF_RX_DN1534
Title 
Size Document Number R e v 
Date: Sheet 
o f 
Honey_Badger_uServer 1B
CPU PCI-E
A3
13 56Tuesday, January 20, 2015
Wiwynn Incorporated
http://www.wiwynn.com
8F, 90, Sec.1, Xintai 5th Rd., Xizhi Dist.,
New Taipei City 22102, Taiwan (R.O.C.)
Title 
Size Document Number R e v 
Date: Sheet 
o f 
Honey_Badger_uServer 1B
CPU PCI-E
A3
13 56Tuesday, January 20, 2015
Wiwynn Incorporated
http://www.wiwynn.com
8F, 90, Sec.1, Xintai 5th Rd., Xizhi Dist.,
New Taipei City 22102, Taiwan (R.O.C.)
Title 
Size Document Number R e v 
Date: Sheet 
o f 
Honey_Badger_uServer 1B
CPU PCI-E
A3
13 56Tuesday, January 20, 2015
Wiwynn Incorporated
http://www.wiwynn.com
8F, 90, Sec.1, Xintai 5th Rd., Xizhi Dist.,
New Taipei City 22102, Taiwan (R.O.C.)
AVOTON 
3 OF 12 U13C
AVOTON-GP
PCIE_OBSN BA38PCIE_OBSP BC38
PCIE_REFCLKN BD49PCIE_REFCLKP BB49
PCIE_RXN15BG34
PCIE_RXN14BF37
PCIE_RXN13BG38
PCIE_RXN12BG41
PCIE_RXN11BH42
PCIE_RXN10BG45
PCIE_RXN9BF46
PCIE_RXN8BH49
PCIE_RXN7BG50
PCIE_RXN6BG53
PCIE_RXN5BF54
PCIE_RXN4BH57
PCIE_RXN3BH58
PCIE_RXN2BK62
PCIE_RXN1BH64
PCIE_RXN0BE64
PCIE_RXP15BE34
PCIE_RXP14BD37
PCIE_RXP13BF38
PCIE_RXP12BE41
PCIE_RXP11BG42
PCIE_RXP10BF45
PCIE_RXP9BD46
PCIE_RXP8BG49
PCIE_RXP7BE50
PCIE_RXP6BF53
PCIE_RXP5BD54
PCIE_RXP4BG57
PCIE_RXP3BG58
PCIE_RXP2BJ62
PCIE_RXP1BJ63
PCIE_RXP0BE63
PCIE_TXN15 BL39
PCIE_TXN14 BK40
PCIE_TXN13 BN41
PCIE_TXN12 BM43
PCIE_TXN11 BL44
PCIE_TXN10 BL46
PCIE_TXN9 BL48
PCIE_TXN8 BM49
PCIE_TXN7 BL50
PCIE_TXN6 BM52
PCIE_TXN5 BL53
PCIE_TXN4 BK54
PCIE_TXN3 BN55
PCIE_TXN2 BN57
PCIE_TXN1 BM58
PCIE_TXN0 BL61
PCIE_TXP15 BN39
PCIE_TXP14 BM40
PCIE_TXP13 BL41
PCIE_TXP12 BP43
PCIE_TXP11 BN44
PCIE_TXP10 BN46
PCIE_TXP9 BN48
PCIE_TXP8 BP49
PCIE_TXP7 BN50
PCIE_TXP6 BL52
PCIE_TXP5 BN53
PCIE_TXP4 BM54
PCIE_TXP3 BL55
PCIE_TXP2 BL57
PCIE_TXP1 BL59
PCIE_TXP0 BK60
R282
402R2F-GP
1 2
R278
100R3F-1-GP
NOPOP
1 2



5
5
4
4
3
3
2
2
1
1
D D
C C
B B
A A
Place resistor as closely as CPU 
Place resistor as closely as CPU 
(With debug port function) 
SATA3_TX_DN0
SATA3_TX_DP0
SATA3_RX_DN0
SATA3_RX_DP0
SATA3_OBS_N
SATA3_OBS_P
SATA3_OBS_N
SATA2_OBS_N
SATA2_OBS_P
SATA3_RX_DP1
SATA3_RX_DN1 SATA3_TX_DN1
SATA3_TX_DP1
BIOS_POST_CMPLT#
BIOS_POST_CMPLT#
CPU_DIAG_LED
CPU_DIAG_LED
XDP_DFX_PORT0
XDP_DFX_PORT1
XDP_DFX_PORT2
XDP_DFX_PORT3
XDP_DFX_PORT4
XDP_DFX_PORT5
XDP_DFX_PORT6
XDP_DFX_PORT7
XDP_DFX_PORT8
XDP_DFX_PORT9
XDP_DFX_PORT10
XDP_DFX_PORT11
XDP_DFX_PORT12
XDP_DFX_PORT13
XDP_DFX_PORT14
XDP_DFX_PORT15
XDP_DFX_PORT_CLK0
XDP_DFX_PORT_CLK1
PD_USB_RCOMP
PD_USB_OBSP
USB_OC#
BD_ID_0 BD_ID_1
USB_P1_DN
USB_P1_DP
SATA2_OBS_N
BD_ID_1BD_ID_0
SATA2_OBS_P
SATA3_OBS_P
SATA2_RX_DP0
SATA2_RX_DN0 SATA2_TX_DN0
SATA2_TX_DP0
BD_ID_2
PD_USB_RCOMP
USB_OC#
BD_REV_0 BD_REV_1 BD_REV_2
P3V3
P3V3P3V3 P3V3_CPU
P3V3_CPU
P3V3_CPU P3V3_CPU P3V3_CPU
SATA3_RX_DN033
SATA3_RX_DP033
SATA3_TX_DN0 33
SATA3_TX_DP0 33
CLK_100M_CPU_SATA3_DP 31
CLK_100M_CPU_SATA3_DN 31
CLK_100M_SATA2_DP31
CLK_100M_SATA2_DN31
XDP_DFX_PORT024
XDP_DFX_PORT124
XDP_DFX_PORT224
XDP_DFX_PORT324
XDP_DFX_PORT424
XDP_DFX_PORT524
XDP_DFX_PORT624
XDP_DFX_PORT724
XDP_DFX_PORT824
XDP_DFX_PORT924
XDP_DFX_PORT1024
XDP_DFX_PORT1124
XDP_DFX_PORT1224
XDP_DFX_PORT1324
XDP_DFX_PORT1424
XDP_DFX_PORT1524
XDP_DFX_PORT_CLK024
XDP_DFX_PORT_CLK124
CLK_96M_CPU_USB_DP 31
CLK_96M_CPU_USB_DN 31
USB_P1_DP 37
USB_P1_DN 37
SATA3_TX_DN1 34
SATA3_TX_DP1 34
SATA3_RX_DN134
SATA3_RX_DP134
SATA2_TX_DP0 37
SATA2_TX_DN0 37
SATA2_RX_DP037
SATA2_RX_DN037
BIOS_POST_CMPLT#38
CPU_DIAG_LED 23
BD_ID_2 15 BD_REV_2 17BD_REV_1 17BD_REV_0 17
Title 
Size Document Number R e v 
Date: Sheet 
o f 
Honey_Badger_uServer 1B
CPU SATA/USB/DFX/BOARD REV
A3
14 56Tuesday, January 20, 2015
Wiwynn Incorporated
http://www.wiwynn.com
8F, 90, Sec.1, Xintai 5th Rd., Xizhi Dist.,
New Taipei City 22102, Taiwan (R.O.C.)
Title 
Size Document Number R e v 
Date: Sheet 
o f 
Honey_Badger_uServer 1B
CPU SATA/USB/DFX/BOARD REV
A3
14 56Tuesday, January 20, 2015
Wiwynn Incorporated
http://www.wiwynn.com
8F, 90, Sec.1, Xintai 5th Rd., Xizhi Dist.,
New Taipei City 22102, Taiwan (R.O.C.)
Title 
Size Document Number R e v 
Date: Sheet 
o f 
Honey_Badger_uServer 1B
CPU SATA/USB/DFX/BOARD REV
A3
14 56Tuesday, January 20, 2015
Wiwynn Incorporated
http://www.wiwynn.com
8F, 90, Sec.1, Xintai 5th Rd., Xizhi Dist.,
New Taipei City 22102, Taiwan (R.O.C.)
TP331
R3084K7R2F-GP 1 2
R415
4K7R2F-GP
1 2
R345
100R3F-1-GP
NOPOP
1 2
R406
1KR2F-3-GP
NOPOP
1 2
R317
1KR2F-3-GP
NOPOP
1 2
R409
4K7R2F-GP
1 2
R403
1KR2F-3-GP
NOPOP
1 2
AVOTON 
5 OF 12 U13E
AVOTON-GP
DFX_PORT15AR59
DFX_PORT14AY65
DFX_PORT13AW66
DFX_PORT12AW64
DFX_PORT11AT59
DFX_PORT10BB63
DFX_PORT9AT60
DFX_PORT8AY59
DFX_PORT7AW62
DFX_PORT6AY63
DFX_PORT5AY56
DFX_PORT4AT54
DFX_PORT3AR57
DFX_PORT2AW58
DFX_PORT1AY58
DFX_PORT0BC64
DFX_PORT_CLK1AV65
DFX_PORT_CLK0AV63
SATA3_GP0 AH51
SATA3_LEDN AH54
SATA3_OBSN R53SATA3_OBSP R55
SATA3_REFCLKN L59SATA3_REFCLKP L57
SATA3_RXN1L65
SATA3_RXN0M64
SATA3_RXP1L63
SATA3_RXP0M62 SATA3_TXN1 R65
SATA3_TXN0 T64
SATA3_TXP1 R63
SATA3_TXP0 R66
SATA_GP0AT63
SATA_LEDNAL49
SATA_OBSNL52 SATA_OBSPJ52
SATA_REFCLKNL54 SATA_REFCLKPJ54
SATA_RXN3C60
SATA_RXN2C62
SATA_RXN1G64
SATA_RXN0H63
SATA_RXP3D60
SATA_RXP2E62
SATA_RXP1G62
SATA_RXP0H62
SATA_TXN3 B53
SATA_TXN2 A54
SATA_TXN1 E57
SATA_TXN0 D57
SATA_TXP3 D53
SATA_TXP2 C54
SATA_TXP1 E58
SATA_TXP0 B57
USB_DN3 BA41
USB_DN2 BB42
USB_DN1 BC45
USB_DN0 BA46
USB_DP3 BB41
USB_DP2 BD42
USB_DP1 BA45
USB_DP0 AY46
USB_OBSP AR48
USB_OC0# AD63
USB_RCOMPI AT46
USB_RCOMPO AT48
USB_REFCLKN BA50USB_REFCLKP BB50
R318
4K7R2F-GP
1 2
R3104K7R2F-GP 1 2
R502
4K7R2F-GP
NOPOP
1 2
R357
402R2F-GP
1 2
R364
402R2F-GP
1 2
R377
1KR2F-3-GP
NOPOP
1 2
R378
1KR2F-3-GP
1 2
R366
100R3F-1-GP
NOPOP
1 2
R124
4K7R2F-GP
1 2
R299
45D3R2F-L-GP
1 2
R485
4K7R2F-GP
1 2
R45
1KR2F-3-GP
NOPOP
1 2
R311 3KR2F-GP1 2
R44
4K7R2F-GP
1 2



5
5
4
4
3
3
2
2
1
1
D D
C C
B B
A A
RTC_CMOS CLEAR 
INTEL RESERVED 
IMPLEMENTATION. 
IF USED, DO NOT 
MODIFY IMPLEMENTATION 
INTEL RESERVED 
IMPLEMENTATION. 
IF USED, DO NOT 
MODIFY IMPLEMENTATION 
AB63_RSVD 
AD53_RSVD 
LPC_CPU_CLKRUN#
LPC_CPU_LAD0
LPC_CPU_LAD1
LPC_CPU_LAD2
LPC_CPU_LAD3
LPC_CPU_FRAME#
LPC_CPU_R_CLKOUT0
SMBUS_HOST_DATA
SMBUS_PECI_DATA
SMBUS_HOST_CLK
SMBUS_PECI_CLK
SMBUS_HOST_ALRT#
CPU_ERR_N0
CPU_ERR_N1
CPU_ERR_N2
FLEX_CLK_SE0
FLEX_CLK_SE1
SPI_CPU_WP#
CLK_100M_CPU_HFHPLL_DN
CLK_100M_CPU_HFHPLL_DP
CLK_14M_CPU
XDP_CPU_RESET#
SPI_CPU_SCLK
SPI_CPU_CS0#
SPI_CPU_MISO
SPI_CPU_MOSI
CTBTRIGOUT
CTBTRIGINOUT
RCOMP_CORE_LVT
XDP_SOC_CPU_TDO
XDP_SOC_CPU_TCK
XDP_SOC_CPU_TDI
XDP_SOC_CPU_TRST#
XDP_SOC_CPU_TMS
XDP_CPU_PRDY#
XDP_CPU_PREQ#
RTC_X2PAD
RTC_X1PAD
RTC_X1PAD
RTC_X2PAD
RTC_EXTPAD
CORE_PWROK_R
SRTCRST_R#
CPU_RSMRST_R#
PU_INTRUDER#
IRQ_CPU_SERIAL
IRQ_CPU_IERR#
IRQ_MCERR_R#
CPU_UART_RXD_R
CPU_UART_TXD_R
SVID_ALERT#
SVID_DATA_R
SVID_CLK_R
IRQ_NMI_R
IRQ_NMI_R
CPU_THERMTRIP#
PROCESSOR_HOT#
MEMORY_CPU_HOT#
SUSPWRDNACK
SUS_STAT#
PU_PMU_GPE#
PMU_SLP_LAN#
PMU_SLP_S3#
PMU_SLP_S45#
PMU_SLP_DDRVTT#
PMU_SUS_CLK_CPU
PMU_WAKE#
PMU_PWRBTN_R#
PMU_PLTRST_R#
TP_CPU_RSVD13
FLEX_CLK_SE0
FLEX_CLK_SE1
IRQ_CPU_SERIAL
XDP_CPU_RESET#
TP_CPU_RSVD0
TP_CPU_RSVD1
TP_CPU_RSVD2
TP_CPU_RSVD6
TP_CPU_RSVD7
TP_CPU_RSVD8
TP_CPU_RSVD9
CPU_RSVD10
TP_CPU_RSVD11
TP_CPU_RSVD12
TP_CPU_RSVD14
TP_CPU_RSVD15
TP_CPU_RSVD16
TP_CPU_RSVD17
SMB_CLK1_SPKR
CPU_FPGA_DISABLE
PMU_RESETBUTTON_R#
XDP_BUF_RTEST#
FPGA_READY#
BD_ID_2
XDP_SOC_CPU_TCK
XDP_SOC_CPU_TDI
XDP_SOC_CPU_TRST#
XDP_SOC_CPU_TMS
XDP_SOC_CPU_TDO
CPU_FPGA_DISABLE
SMBUS_SW_R_EN
SMBUS_SW_R_EN
LPC_CPU_R_CLKOUT1
IRQ_CPU_IERR#
IRQ_MCERR#
P3V3_RTC
P3V3
P1V0
P3V3
P3V3_CPU
P3V3 P3V3
P3V3_CPU
P3V3
P3V3 P3V3
LPC_CPU_LAD038
LPC_CPU_LAD138
LPC_CPU_LAD238
LPC_CPU_LAD338
LPC_CPU_CLKRUN#16,39
LPC_CPU_FRAME#16,38
CLK_100M_CPU_HFHPLL_DP31
CLK_100M_CPU_HFHPLL_DN31
CLK_14M_CPU31
XDP_CPU_RESET#24
SPI_CPU_MISO 25
SPI_CPU_SCLK 25
SPI_CPU_CS0# 16,25
SPI_CPU_MOSI 25
XDP_SOC_CPU_TDO 24,36
XDP_SOC_CPU_TCK24,36
XDP_SOC_CPU_TDI24,36
XDP_SOC_CPU_TRST#24,36
XDP_SOC_CPU_TMS24,36
SMBUS_PECI_CLK16,22
SMBUS_HOST_CLK16,22,24,32
SMBUS_PECI_DATA16,22
SMBUS_HOST_DATA16,22,24,32
SMBUS_HOST_ALRT#16
CPU_ERR_N016,38
CPU_ERR_N116,38
CPU_ERR_N216,39
XDP_CPU_PREQ# 24
XDP_CPU_PRDY# 24
CORE_PWROK 22,24
CPU_RSMRST# 16,24,35,37,39,46
XDP_BUF_RTEST# 24
IRQ_CPU_SERIAL 38
IRQ_CPU_IERR# 53
IRQ_MCERR# 53
CPU_TXD 37
CPU_RXD 37
SVID_CPU_ALERT# 16,50,51
SVID_CPU_CLK 16,50,51
SVID_CPU_DATA 16,50,51
IRQ_NMI 38
CPU_THERMTRIP# 22
PROCESSOR_HOT# 22
MEMORY_CPU_HOT# 22
SUSPWRDNACK 16
PMU_SLP_S45#16,22,38,51
PMU_SLP_S3#16,50,52
PMU_SUS_CLK16,34
PMU_PWRBTN_R#53
PMU_PLTRST#34,37,38,53
LPC_CPU_CLKOUT038
PU_PMU_GPE#16
SPI_CPU_WP#25
PMU_SLP_DDRVTT#52
SRTCRST# 23
FPGA_READY#38
BD_ID_214
SMB_CLK1_SPKR16,23
CPU_FPGA_DISABLE 39
PMU_WAKE#16
SMBUS_SW_EN16,22
PMU_RESETBUTTON#53
Title 
Size Document Number R e v 
Date: Sheet 
o f 
Honey_Badger_uServer 1B
CPU MISC SIGNAL
A3
15 56Tuesday, January 20, 2015
Wiwynn Incorporated
http://www.wiwynn.com
8F, 90, Sec.1, Xintai 5th Rd., Xizhi Dist.,
New Taipei City 22102, Taiwan (R.O.C.)
Title 
Size Document Number R e v 
Date: Sheet 
o f 
Honey_Badger_uServer 1B
CPU MISC SIGNAL
A3
15 56Tuesday, January 20, 2015
Wiwynn Incorporated
http://www.wiwynn.com
8F, 90, Sec.1, Xintai 5th Rd., Xizhi Dist.,
New Taipei City 22102, Taiwan (R.O.C.)
Title 
Size Document Number R e v 
Date: Sheet 
o f 
Honey_Badger_uServer 1B
CPU MISC SIGNAL
A3
15 56Tuesday, January 20, 2015
Wiwynn Incorporated
http://www.wiwynn.com
8F, 90, Sec.1, Xintai 5th Rd., Xizhi Dist.,
New Taipei City 22102, Taiwan (R.O.C.)
R82
10KR2F-2-GP
1 2
R3851R2F-2-GP NOPOP12
R92
10MR3F-GP
1 2
R304 0R2J-2-GP1 2
SW3
SW-PUSH-2P-6-GP
NOPOP
21
AVOTON 
6 OF 12 U13F
AVOTON-GP
UART1_TXD AH50UART1_RXD AG50
THERMTRIP# AT56
TDO AF63
SVID_DATA AW53SVID_CLK BB60SVID_ALERT# BC62
SUS_STAT# AB65
SUSPWRDNACK Y57
SRTCRST# AD49
SPI_MOSI AB62SPI_MISO AD59
SPI_CS0# Y65SPI_CS1# AC58
SPI_CLK AF46
SMB_DATA0AP62 SMB_DATA1AN63 SMB_DATA2AN65
SMB_CLK0AN62 SMB_CLK1AR63 SMB_CLK2AR65
SMBALRT0#AL58 RTEST# AD50
RSMRST# AC47
RCOMP_CORE_LVT AG46PROCHOT# BB59
PMU_WAKE#AD66 PMU_SUSCLKAD58
PMU_SLP_S45#V64 PMU_SLP_S3#AF65 PMU_SLP_LAN#Y50 PMU_SLP_DDRVTT#AC52
PMU_RESETBUTTON#AM58 PMU_PWRBTN#AC49 PMU_PLTRST#AE62 AB63_RSVDAB63 AA47_RSVDAA47
NMI AL56
MEMHOT# AL46MCERR# AL52
LPC_FRAME#AH56 LPC_CLKRUN#AH48
AD53_RSVD AD53ILB_SEIRQ AT50IERR# AM52
HPLL_REFPL37
HPLL_REFNJ37
CX_PREQ# AY53CX_PRDY# AW56
CTBTRIGOUTAL47
CTBTRIGINOUTAM47
CPU_RESET#Y63
COREPWROK AH60
CLK14_INAM56
BVCCRTC_EXTPAD AD55
BRTCX2_PAD AJ63BRTCX1_PAD AJ65
TCKAD65
TDIAC56
TMSAC53
TRST#AA46
RSVD16 L38RSVD17 J38
RSVD15 P38
RSVD10 AG60
RSVD14 R37
Y59_RSVD Y59
RSVD12 AC25
RSVD11 AC26
RSVD5 AR51
RSVD8 AL34RSVD9 AJ34
RSVD7 AP20
RSVD6 AP21
RSVD4 AR53
RSVD3 AR54
RSVD2 AT34
RSVD1 AT51
RSVD0 AU34
ERROR2#AL63
ERROR1#AL62
ERROR0#AL65
GPIO_SUS2T53
GPIO_SUS1W54
GPIO_SUS0V66
FLEX_CLK_SE1AG56
FLEX_CLK_SE0AH59
LPC_AD3AG59
LPC_AD2AL53
LPC_AD1AM53
LPC_AD0AG54
LPC_CLKOUT1AM49
LPC_CLKOUT0AG51R376 33R2F-3-GP1 2
R3370R2J-2-GP NOPOP1 2
TP321
C26
SC6P50V2CN-1GP
1 2
TP71
TP311
R93
1KR2F-3-GP
NOPOP
12
TP471
R352 0R2J-2-GP1 2
R302 0R2J-2-GP1 2
R307 0R2J-2-GP1 2
R29222R2F-1-GP1 2
TP251
R291 220R2F-GP1 2
R94
10KR2F-2-GP
1 2
R300 0R2J-2-GP1 2
TP60
TPAD32-GP 1
R329 0R2J-2-GP1 2
R107
4K7R2F-GP
NOPOP
1 2
R283 0R2J-2-GP1 2
C33
SC6P50V2CN-1GP
1 2
R477
10KR2F-2-GP
1 2
R108
4K7R2F-GP
NOPOP
1 2
TP221
R320 49D9R2F-GP1 2
R322 0R2J-2-GP1 2
TP61
TPAD32-GP 1
R47
51R2F-2-GP
NOPOP12
TP341
R324 0R2J-2-GP1 2
TP521
R33433R2F-3-GP 12
R33022R2F-1-GP1 2
TP481
C122
SCD1U16V2KX-3GP
NOPOP
12
R55 0R2J-2-GP12
R323
10KR2F-2-GP
1 2
TP511
R416
10KR2F-2-GP
NOPOP
1 2
TP50
TPAD32-GP 1
R295
10KR2F-2-GP
NOPOP
1 2
R81
1KR2F-3-GP
NOPOP
1 2
R478
10KR2F-2-GP
1 2
TP361
R114
4K7R2F-GP
NOPOP
1 2
C200 SCD1U16V2KX-3GP1 2
TP231
TP53
TPAD32-GP 1
TP271
TP241
R294
1KR2F-3-GP
1 2
R331 1MR3F-GP1 2
R288 0R2J-2-GP1 2
TP291
X1
X-32D768KHZ-56GP
1 2
R298
10KR2F-2-GP
NOPOP
1 2
TP66TPAD28-1-GP-U 1
R296
10KR2F-2-GP
NOPOP
1 2
TP59
TPAD32-GP 1



5
5
4
4
3
3
2
2
1
1
D D
C C
B B
A A
CPU_ERR_N0
CPU_ERR_N1
CPU_ERR_N2
LPC_CPU_CLKRUN#
LPC_CPU_FRAME#
SUSPWRDNACK
PMU_SLP_S45#
PMU_SLP_S3#
PU_PMU_GPE#
PMU_WAKE#
PMU_SUS_CLK
CPU_RSMRST#
SPI_CPU_CS0#
P3V3
P3V3
P3V3
P3V3_CPU
P1V0
SMBUS_PECI_DATA 15,22
SMBUS_SW_EN 15,22
SMBUS_HOST_DATA 15,22,24,32
SMBUS_HOST_CLK 15,22,24,32
SMB_CLK1_SPKR 15,23
SMBUS_PECI_CLK 15,22
LPC_CPU_FRAME# 15,38
LPC_CPU_CLKRUN# 15,39
CPU_ERR_N0 15,38
CPU_ERR_N1 15,38
CPU_ERR_N2 15,39
SMBUS_HOST_ALRT# 15
PU_PMU_GPE# 15
PMU_SUS_CLK 15,34
SUSPWRDNACK 15
PMU_SLP_S3# 15,50,52
PMU_SLP_S45# 15,22,38,51
PMU_WAKE# 15
SVID_CPU_ALERT# 15,50,51
SVID_CPU_CLK 15,50,51
SVID_CPU_DATA 15,50,51
CPU_RSMRST# 15,24,35,37,39,46
SPI_CPU_CS0# 15,25
Title 
Size Document Number R e v 
Date: Sheet 
o f 
Honey_Badger_uServer 1B
CPU SMB/LPC/SVID PULL-UP
A3
16 56Tuesday, January 20, 2015
Wiwynn Incorporated
http://www.wiwynn.com
8F, 90, Sec.1, Xintai 5th Rd., Xizhi Dist.,
New Taipei City 22102, Taiwan (R.O.C.)
Title 
Size Document Number R e v 
Date: Sheet 
o f 
Honey_Badger_uServer 1B
CPU SMB/LPC/SVID PULL-UP
A3
16 56Tuesday, January 20, 2015
Wiwynn Incorporated
http://www.wiwynn.com
8F, 90, Sec.1, Xintai 5th Rd., Xizhi Dist.,
New Taipei City 22102, Taiwan (R.O.C.)
Title 
Size Document Number R e v 
Date: Sheet 
o f 
Honey_Badger_uServer 1B
CPU SMB/LPC/SVID PULL-UP
A3
16 56Tuesday, January 20, 2015
Wiwynn Incorporated
http://www.wiwynn.com
8F, 90, Sec.1, Xintai 5th Rd., Xizhi Dist.,
New Taipei City 22102, Taiwan (R.O.C.)
R289
100R2F-L1-GP-U
1 2
R314
10KR2F-2-GP
NOPOP
1 2
R284
4K7R2F-GP
NOPOP
1 2
R111
1KR2F-3-GP
NOPOP
1 2
R3134K7R2F-GP 1 2
R112
10KR2F-2-GP
1 2
R103
1KR2F-3-GP
1 2
R293
56D2R2F-GP
1 2
R704K7R2F-GP 1 2
R99
10KR2F-2-GP
NOPOP
1 2
R714K7R2F-GP 1 2
R358
10KR2F-2-GP
NOPOP
1 2
R3164K7R2F-GP 1 2
R734K7R2F-GP
NOPOP
1 2
R121
10KR2F-2-GP
1 2
R724K7R2F-GP
NOPOP
1 2
R332
1KR2F-3-GP
NOPOP
1 2
R117
10KR2F-2-GP
NOPOP
1 2
R684K7R2F-GP
NOPOP
1 2
R674K7R2F-GP 1 2
R321
2K2R2F-GP
1 2
R3064K7R2F-GP 1 2
R664K7R2F-GP 1 2



5
5
4
4
3
3
2
2
1
1
D D
C C
B B
A A
BD_REV_0
BD_REV_1
MSATA_PRESENT#
GBE_OBSP
GBE_OBSN
GBE_OBSP
GBE_OBSN
GBE_SMBALRT#
GBE_SMBCLK
SPI_MISO_R_GBE
SPI_CS_GBE#
SPI_CLK_GBE
SPI_CLK_GBE_R
SPI_GBE_HOLD#SO_GBESPI_MISO_R_GBE
GBE_WOL
GBE_SMBALRT#
SPI_MOSI_GBE
SPI_MOSI_GBE_R
GBE_SDP0
GBE_SMBDATA
GBE_SMBALRT#
GBE_SMBCLK
GBE_MDIO_DATA0
GBE_MDIO_CLK0
NGFF_PRESENT#
CPU_GBE_RX_DN0
CPU_GBE_RX_DP0
CPU_GBE_TX_DN0
CPU_GBE_TX_DP0
GBE_MDIO_DATA0
GBE_MDIO_CLK0
GBE_SMBDATA
GBE_WOL
REV_CPU_FPGA_IO0
REV_CPU_FPGA_IO1
REV_CPU_FPGA_IO0
REV_CPU_FPGA_IO1
SPI_MOSI_GBE
SPI_CLK_GBE
SPI_CS_GBE#
GBE_SDP0
BD_REV_2
P3V3_CPU
P3V3_CPU
P3V3_CPU
P3V3_CPU
P3V3_CPU
CLK_100M_CPU_GBE_DN31
CLK_100M_CPU_GBE_DP31
CPU_GBE_RX_DN037
CPU_GBE_RX_DP037
CPU_GBE_TX_DN0 37
CPU_GBE_TX_DP0 37
MSATA_PRESENT#33
NGFF_PRESENT#34
GBE_SMBCLK 37
GBE_SMBALRT# 37
GBE_SMBDATA 37
REV_CPU_FPGA_IO038
REV_CPU_FPGA_IO138
BD_REV_014
BD_REV_114
BD_REV_2 14
Title 
Size Document Number R e v 
Date: Sheet 
o f 
Honey_Badger_uServer 1B
CPU GB LAN
A3
17 56Tuesday, January 20, 2015
Wiwynn Incorporated
http://www.wiwynn.com
8F, 90, Sec.1, Xintai 5th Rd., Xizhi Dist.,
New Taipei City 22102, Taiwan (R.O.C.)
Title 
Size Document Number R e v 
Date: Sheet 
o f 
Honey_Badger_uServer 1B
CPU GB LAN
A3
17 56Tuesday, January 20, 2015
Wiwynn Incorporated
http://www.wiwynn.com
8F, 90, Sec.1, Xintai 5th Rd., Xizhi Dist.,
New Taipei City 22102, Taiwan (R.O.C.)
Title 
Size Document Number R e v 
Date: Sheet 
o f 
Honey_Badger_uServer 1B
CPU GB LAN
A3
17 56Tuesday, January 20, 2015
Wiwynn Incorporated
http://www.wiwynn.com
8F, 90, Sec.1, Xintai 5th Rd., Xizhi Dist.,
New Taipei City 22102, Taiwan (R.O.C.)
R139
10KR2F-2-GP
1 2
R362
10KR2F-2-GP
1 2
TP46
1
R367
1KR2F-3-GP
1 2
R180 0R2J-2-GP1 2
R344
10KR2F-2-GP
NOPOP
1 2
R372
402R2F-GP
1 2 R145
4K7R2F-GP
1 2
U21
AT25256B-SSHL-T-GP
CS#1
SO2
WP#3
GND4 SI 5SCK 6HOLD# 7VCC 8
R365
0R2J-2-GP
NOPOP
1 2
C76
SC1U10V2KX-1GP
1 2R119
10KR2F-2-GP
NOPOP
1 2
TP45
1
R122
10KR2F-2-GP
NOPOP
1 2
R169
15R2F-2-GP
1 2
R375
10KR2F-2-GP
1 2
R174 0R2J-2-GP1 2
R457
10KR2F-2-GP
NOPOP
1 2
R456
10KR2F-2-GP
NOPOP
1 2
TP49
1
R371
1KR2F-3-GP
NOPOP
1 2
AVOTON 
4 OF 12 U13D
AVOTON-GP
GBE_EE_CS_N R59
GBE_EE_DI W51
GBE_EE_DO W60
GBE_EE_SK T50
GBE_LED3R58
GBE_LED2P48
GBE_LED1W50
GBE_LED0P46
GBE_MDIO0_I2C_CLKW56
GBE_MDIO0_I2C_DATAW59
GBE_MDIO1_I2C_CLKY54
GBE_MDIO1_I2C_DATAY53
GBE_OBSNH50 GBE_OBSPG50
GBE_REFCLKND50 GBE_REFCLKPB50
GBE_RXN3H42
GBE_RXN2L44
GBE_RXN1L46
GBE_RXN0K48
GBE_RXP3G42
GBE_RXP2J44
GBE_RXP1J46
GBE_RXP0H48
GBE_SDP01 T48
GBE_SDP0_0 T58
GBE_SMBALRT# T55
GBE_SMBCLK P50
GBE_SMBD T59
GBE_TXN3 A42
GBE_TXN2 B44
GBE_TXN1 B46
GBE_TXN0 B48
GBE_TXP3 C42
GBE_TXP2 D44
GBE_TXP1 D46
GBE_TXP0 D48
GBE_WOL V63



5
5
4
4
3
3
2
2
1
1
D D
C C
B B
A A
2A\120ohm\0603 
2A\120ohm\0603 
2A\120ohm\0603 
2A\120ohm\0603 
VCCRAMCPUSI1_SENSE
VSSRAMCPUSI1_SENSE
AVV_VCCCPUVIDSIO_1P03_SENSE
AVV_VSSCPUVIDSIO_1P03_SENSE
P1V0_STBY
P1V0
VCCACKDDR1
VCCACKDDR0
P1V0
P1V0_STBY
P1V0
P1V0
P1V0
P1V0_STBY
P1V0
P1V0
P1V0_STBY
VCCA_PLLDDR1_AVN
VCCA_PLLDDR0_AVN
PVNN
P1V0 VCCACKDDR0
VCCACKDDR1
P1V0
P1V0
P1V0
P1V0 VCCA_PLLDDR1_AVN
P1V0 VCCA_PLLDDR0_AVN
P1V0
P1V0
P1V0
P1V0
P1V0
P1V0
P1V0
AVV_VCCCPUVIDSIO_1P03_SENSE 50
AVV_VSSCPUVIDSIO_1P03_SENSE 50
VCCRAMCPUSI1_SENSE 48
Title 
Size Document Number Rev 
Date: Sheet o f 
Honey_Badger_uServer 1B
CPU POWER1/2
A2
18 56Tuesday, January 20, 2015
Wiwynn Incorporated
http://www.wiwynn.com
8F, 90, Sec.1, Xintai 5th Rd., Xizhi Dist.,
New Taipei City 22102, Taiwan (R.O.C.)
Title 
Size Document Number Rev 
Date: Sheet o f 
Honey_Badger_uServer 1B
CPU POWER1/2
A2
18 56Tuesday, January 20, 2015
Wiwynn Incorporated
http://www.wiwynn.com
8F, 90, Sec.1, Xintai 5th Rd., Xizhi Dist.,
New Taipei City 22102, Taiwan (R.O.C.)
Title 
Size Document Number Rev 
Date: Sheet o f 
Honey_Badger_uServer 1B
CPU POWER1/2
A2
18 56Tuesday, January 20, 2015
Wiwynn Incorporated
http://www.wiwynn.com
8F, 90, Sec.1, Xintai 5th Rd., Xizhi Dist.,
New Taipei City 22102, Taiwan (R.O.C.)
L7
BLM18PG121SN1D-GP
1 2
C163
SC1U10V2KX-1GP
1 2
C199
SC2D2U10V2KX-GP
1 2
C171
SC1U10V2KX-1GP
1 2
C210
SC2D2U10V2KX-GP
1 2
C185
SC2D2U10V2KX-GP
1 2C119
SC1U25V3KX-GP
1 2
L9
BLM18PG121SN1D-GP
1 2
C133
SC1U10V2KX-1GP
1 2
C254
SC1U10V2KX-1GP
1 2
C145
SC1U10V2KX-1GP
1 2C258
SC1U25V3KX-GP
1 2
C229
SC1U10V2KX-1GP
1 2
C203
SC1U10V2KX-1GP
1 2
C252
SC1U10V2KX-1GP
1 2
C217
SC1U10V2KX-1GP
1 2
C251
SC2D2U10V2KX-GP
1 2
C151
SC1U10V2KX-1GP
1 2
C225
SC1U10V2KX-1GP
1 2
C147
SC1U10V2KX-1GP
1 2
AVOTON 
8 OF 12 U13H
AVOTON-GP
VCCACKDDR_0_1P0AT32
VCCACKDDR_0_1P0AU32
VCCACKDDR_1_1P0V28
VCCACKDDR_1_1P0W28
VCCADDR_0_1P0AT21
VCCADDR_0_1P0AT23
VCCADDR_0_1P0AT25
VCCADDR_0_1P0AT26
VCCADDR_0_1P0AT28
VCCADDR_1_1P0W21
VCCADDR_1_1P0W23
VCCADDR_1_1P0W25
VCCADDR_1_1P0W26
VCCADDR_1_1P0AA21
VCCADLLDDR_0_1P0AU21
VCCADLLDDR_0_1P0AU23
VCCADLLDDR_0_1P0AU25
VCCADLLDDR_0_1P0AU26
VCCADLLDDR_0_1P0AU28
VCCADLLDDR_1_1P0V20
VCCADLLDDR_1_1P0V21
VCCADLLDDR_1_1P0V23
VCCADLLDDR_1_1P0V25
VCCADLLDDR_1_1P0V26
VCCAPLL_GBE_1P0 V41
VCCAPLL_GBE_1P0 W41
VCCAPLL_PCIE_1P0 AY37
VCCAPLL_PCIE_1P0 BA37
VCCAPLL_SATA3_1P0 R44
VCCAPLL_SATA3_1P0 T44
VCCAPLL_SATA_1P0 R46
VCCAPLL_SATA_1P0 T45
VCCAREF_GBE_HVGEN T39
VCCAREF_GBE_HVGEN V39
VCCAREF_PCIE_HVGEN AT39
VCCAREF_SATA_HVGEN V46
VCCAREF_SATA_HVGEN W44
VCCAREF_SATA_HVGEN W46
VCCAUSB_1P0 AT42
VCCA_GBE_1P0T37
VCCA_GBE_1P0V38
VCCA_GBE_1P0W38
VCCA_PCIE_1P0AT36
VCCA_PCIE_1P0AT38
VCCA_PCIE_1P0AU36
VCCA_PCIE_1P0AU38
VCCA_PCIE_1P0AU39
VCCA_PCIE_1P0AW36
VCCA_PCIE_1P0AW38
VCCA_PCIE_1P0AW39
VCCA_SATA3_1P0P42
VCCA_SATA3_1P0N42
VCCA_SATA3_1P0L42
VCCA_SATA_1P0L41
VCCA_SATA_1P0N41
VCCA_SATA_1P0K41
VCCA_SATA_1P0P41
VCCCPUVIDSI0_1P03_SENSE AE3
VCCDUSBSUS_1P0 AT41
VCCDUSB_1P0 AU41
VCCDUSB_1P0 AW41
VCCPLLDDR_0_1P0 AU31VCCPLLDDR_1_1P0 W31
VCCRAMCPUSI1_1P03_SENSE AF32
VNN AD36
VNN AD39
VNN AF36
VNN AF39
VNN AG36
VNN AG39
VNN AJ36
VNN AJ39
VNN AL36
VNN AL39
VNN AM25
VNN AM26
VNN AM28
VNN AM29
VNN AM31
VNN AM32
VNN AM34
VNN AM36
VNN AM38
VNN AM39
VNN AM41
VNN AM42
VSSCPUVIDSI0_1P03_SENSE AF2
VSSRAMCPUSI1_1P03_SENSE AF34
C169
SC1U10V2KX-1GP
1 2
C226
SC1U10V2KX-1GP
1 2
C204
SC1U10V2KX-1GP
1 2
C124
SC1U10V2KX-1GP
1 2
C253
SC1U10V2KX-1GP
1 2
C153
SC1U10V2KX-1GP
1 2
C167
SC1U10V2KX-1GP
1 2
C218
SC1U10V2KX-1GP
1 2
C224
SC1U10V2KX-1GP
1 2
C219
SC1U10V2KX-1GP
1 2
C150
SC1U10V2KX-1GP
1 2
C187
SC1U10V2KX-1GP
1 2
C213
SC1U10V2KX-1GP
1 2
C220
SC1U10V2KX-1GP
1 2
C180
SC1U10V2KX-1GP
1 2
C214
SC2D2U10V2KX-GP
1 2
C166
SC1U10V2KX-1GP
1 2
L6
BLM18PG121SN1D-GP
1 2
C259
SC1U10V2KX-1GP
1 2
C155
SC1U10V2KX-1GP
1 2
C211
SC1U10V2KX-1GP
1 2
R333
100KR2F-L1-GP
1 2
C261
SC1U10V2KX-1GP
1 2
C9
SC22U6D3V5MX-2GP
1 2
L5
BLM18PG121SN1D-GP
1 2
C205
SC2D2U10V2KX-GP
1 2



5
5
4
4
3
3
2
2
1
1
D D
C C
B B
A A
VCCRAMCPUSI0GT_MOD3_1P03
VCCCORE6VIDSI0GT_1P03
VCCCORE7VIDSI0GT_1P03
P3V3_CPU
P3V3
P3V3_RTC
P1V8
PV_VDDR
PV_VDDR
VCCCLKDDR1
VCCCLKDDR0
P1V35
PV_VDDR
P1V0_STBY
P1V0
P1V1
P1V0_STBY
P1V0
PVCCP
PV_VDDR
P3V3_CPU
P1V8 P3V3P1V8_STBY
P1V0
P1V1
VCCCLKDDR0
P1V8_STBY
VCCCLKDDR1
Title 
Size Document Number Rev 
Date: Sheet o f 
Honey_Badger_uServer 1B
CPU POWER2/2
A2
19 56Tuesday, January 20, 2015
Wiwynn Incorporated
http://www.wiwynn.com
8F, 90, Sec.1, Xintai 5th Rd., Xizhi Dist.,
New Taipei City 22102, Taiwan (R.O.C.)
Title 
Size Document Number Rev 
Date: Sheet o f 
Honey_Badger_uServer 1B
CPU POWER2/2
A2
19 56Tuesday, January 20, 2015
Wiwynn Incorporated
http://www.wiwynn.com
8F, 90, Sec.1, Xintai 5th Rd., Xizhi Dist.,
New Taipei City 22102, Taiwan (R.O.C.)
Title 
Size Document Number Rev 
Date: Sheet o f 
Honey_Badger_uServer 1B
CPU POWER2/2
A2
19 56Tuesday, January 20, 2015
Wiwynn Incorporated
http://www.wiwynn.com
8F, 90, Sec.1, Xintai 5th Rd., Xizhi Dist.,
New Taipei City 22102, Taiwan (R.O.C.)
C176
SC1U10V2KX-1GP
1 2
C240
SC1U10V2KX-1GP
1 2
TP26
1
C148
SC1U10V2KX-1GP
1 2
C157
SC1U10V2KX-1GP
1 2
C188
SC22U6D3V5MX-2GP
1 2
C143
SCD1U16V2JX-1-GP
1 2
C256
SC1U10V2KX-1GP
1 2
C129
SC1U10V2KX-1GP
1 2
C175
SC1U10V2KX-1GP
1 2
L4
BLM18PG121SN1D-GP
1 2
C132
SC1U10V2KX-1GP
1 2
C228
SC1U10V2KX-1GP
1 2
TP28
1
C245
SC1U10V2KX-1GP
1 2
C255
SC10U6D3V3MX-GP
1 2
C126
SC22U6D3V5MX-2GP
1 2
C156
SC1U10V2KX-1GP
1 2
C178
SC1U10V2KX-1GP
1 2
C195
SC1U10V2KX-1GP
1 2
C130
SC1U10V2KX-1GP
1 2
C182
SC1U10V2KX-1GP
1 2
C257
SCD1U16V2JX-1-GP
1 2
C174
SC1U10V2KX-1GP
1 2
C131
SC1U10V2KX-1GP
1 2
C198
SC1U10V2KX-1GP
1 2
C154
SCD1U16V2JX-1-GP
1 2
C117
SC10U6D3V3MX-GP
1 2
C118
SC1U10V2KX-1GP
1 2
C194
SC1U10V2KX-1GP
1 2
C179
SC22U6D3V5MX-2GP
1 2
AVOTON 
7 OF 12 U13G
AVOTON-GP
VCCCLKDDR_0_1P5AT29
VCCCLKDDR_0_1P5AU29
VCCCLKDDR_1_1P5V29
VCCCLKDDR_1_1P5W29
VCCCORE6VIDSI0GT_1P03 AL32VCCCORE7VIDSI0GT_1P03 AL31
VCCCPUVIDSI0_1P03 AD21
VCCCPUVIDSI0_1P03 AD23
VCCCPUVIDSI0_1P03 AD25
VCCCPUVIDSI0_1P03 AD26
VCCCPUVIDSI0_1P03 AE1
VCCCPUVIDSI0_1P03 AE5
VCCCPUVIDSI0_1P03 AF20
VCCCPUVIDSI0_1P03 AF21
VCCCPUVIDSI0_1P03 AF23
VCCCPUVIDSI0_1P03 AF25
VCCCPUVIDSI0_1P03 AF26
VCCCPUVIDSI0_1P03 AF4
VCCCPUVIDSI0_1P03 AG11
VCCCPUVIDSI0_1P03 AG13
VCCCPUVIDSI0_1P03 AG14
VCCCPUVIDSI0_1P03 AG17
VCCCPUVIDSI0_1P03 AG19
VCCCPUVIDSI0_1P03 AG21
VCCCPUVIDSI0_1P03 AG7
VCCCPUVIDSI0_1P03 AG8
VCCCPUVIDSI0_1P03 AH1
VCCCPUVIDSI0_1P03 AH10
VCCCPUVIDSI0_1P03 AH13
VCCCPUVIDSI0_1P03 AH14
VCCCPUVIDSI0_1P03 AH16
VCCCPUVIDSI0_1P03 AH19
VCCCPUVIDSI0_1P03 AH3
VCCCPUVIDSI0_1P03 AH4
VCCCPUVIDSI0_1P03 AH7
VCCCPUVIDSI0_1P03 AH8
VCCCPUVIDSI0_1P03 AJ2
VCCCPUVIDSI0_1P03 AJ21
VCCCPUVIDSI0_1P03 AJ23
VCCCPUVIDSI0_1P03 AJ25
VCCCPUVIDSI0_1P03 AJ26
VCCCPUVIDSI0_1P03 AJ4
VCCCPUVIDSI0_1P03 AJ5
VCCCPUVIDSI0_1P03 AK20
VCCCPUVIDSI0_1P03 AL21
VCCCPUVIDSI0_1P03 AL23
VCCCPUVIDSI0_1P03 AL25
VCCCPUVIDSI0_1P03 AL26
VCCDDR_0_1P5AY19
VCCDDR_0_1P5AY21
VCCDDR_0_1P5AY23
VCCDDR_0_1P5BC10
VCCDDR_0_1P5BC13
VCCDDR_0_1P5BC15
VCCDDR_0_1P5BC7
VCCDDR_0_1P5BD17
VCCDDR_0_1P5BD21
VCCDDR_0_1P5BD25
VCCDDR_0_1P5BE19
VCCDDR_0_1P5BE26
VCCDDR_0_1P5BF13
VCCDDR_0_1P5BF23
VCCDDR_0_1P5BG15
VCCDDR_0_1P5BG9
VCCDDR_0_1P5BH17
VCCDDR_0_1P5BJ4
VCCDDR_0_1P5BK12
VCCDDR_0_1P5BK13
VCCDDR_0_1P5BK6
VCCDDR_0_1P5BK9
VCCDDR_0_1P5BL7
VCCDDR_0_1P5BM9
VCCDDR_1_1P5E7
VCCDDR_1_1P5E9
VCCDDR_1_1P5G5
VCCDDR_1_1P5G7
VCCDDR_1_1P5H13
VCCDDR_1_1P5H14
VCCDDR_1_1P5J5
VCCDDR_1_1P5K10
VCCDDR_1_1P5K17
VCCDDR_1_1P5K18
VCCDDR_1_1P5K25
VCCDDR_1_1P5K26
VCCDDR_1_1P5L21
VCCDDR_1_1P5L22
VCCDDR_1_1P5L5
VCCDDR_1_1P5M3
VCCDDR_1_1P5N13
VCCDDR_1_1P5N14
VCCDDR_1_1P5P17
VCCDDR_1_1P5P18
VCCDDR_1_1P5P25
VCCDDR_1_1P5P26
VCCDDR_1_1P5R21
VCCDDR_1_1P5R22
VCCDIGXXXSI0_1P03 AD38
VCCDIGXXXSI0_1P03 AF38
VCCDIGXXXSI0_1P03 AG38
VCCDIGXXXSI0_1P03 AJ38
VCCDIGXXXSUS_1P03 AA38
VCCDIGXXXSUS_1P03 AA39
VCCDIGXXXSUS_1P03 AA41
VCCDIGXXXSUS_1P03 AC38
VCCDIGXXXSUS_1P03 AC39
VCCDIGXXXSUS_1P03 AC41
VCCFHVCPUSI0_MOD0_1P03 AD28VCCFHVCPUSI0_MOD1_1P03 AL28VCCFHVCPUSI0_MOD2_1P03 AD29VCCFHVCPUSI0_MOD3_1P03 AJ29
VCCFHVSOCSI0_1P03 AC42
VCCFHVSOCSI0_1P03 AC44
VCCPADXXXSI0_1P8AJ41
VCCPADXXXSI0_1P8AL41
VCCPADXXXSI0_3P3AJ42
VCCPADXXXSUS_1P8AF41
VCCPADXXXSUS_1P8AF42
VCCPADXXXSUS_3P3AD42
VCCPADXXXSUS_3P3AD44
VCCRAMCPUSI0GT_MOD3_1P03 AJ31
VCCRAMCPUSI1_1P03 AD31
VCCRAMCPUSI1_1P03 AD32
VCCRAMCPUSI1_1P03 AF29
VCCRAMCPUSI1_1P03 AF31
VCCRAMCPUSI1_1P03 AG29
VCCRAMCPUSI1_1P03 AG31
VCCRAMCPUSI1_1P03 AG32
VCCRTC_3P3AG42
VCCSFRPLLDDR_0_1P5AT31 VCCSFRPLLDDR_1_1P5V31
VCCSFRXXXSI0_1P35V34
VCCSFRXXXSI0_1P35W34
VCCSFRXXXSI0_1P35AA32
VCCSFRXXXSI0_1P35AA34
VCCUSBSUS_1P8AU46
VCCUSBSUS_1P8AU47
VCCUSBSUS_3P3AU42
VCCUSBSUS_3P3AW42
C238
SC1U10V2KX-1GP
1 2
C186
SC1U10V2KX-1GP
1 2
C123
SC1U10V2KX-1GP
1 2
C237
SC1U10V2KX-1GP
1 2
C215
SC1U10V2KX-1GP
1 2
C241
SC1U10V2KX-1GP
1 2
C260
SC22U6D3V5MX-2GP
1 2
C216
SC1U10V2KX-1GP
1 2
C230
SCD1U16V2KX-3GP
1 2
C168
SC22U6D3V5MX-2GP
1 2
C127
SCD1U16V2KX-3GP
1 2
C128
SC1U10V2KX-1GP
1 2
C246
SC1U10V2KX-1GP
1 2
C142
SC1U10V2KX-1GP
1 2
L8
BLM18PG121SN1D-GP
1 2
C190
SC1U10V2KX-1GP
1 2
C242
SC1U10V2KX-1GP
1 2
TP30
1
C183
SCD1U16V2KX-3GP
1 2
C221
SC1U10V2KX-1GP
1 2
C212
SC1U10V2KX-1GP
1 2
C146
SC1U10V2KX-1GP
1 2
C243
SC1U10V2KX-1GP
1 2
C152
SC1U10V2KX-1GP
1 2
C202
SC1U10V2KX-1GP
1 2
C239
SC1U10V2KX-1GP
1 2
C193
SC1U10V2KX-1GP
1 2
C161
SC22U6D3V5MX-2GP
1 2
C160
SC1U10V2KX-1GP
1 2



5
5
4
4
3
3
2
2
1
1
D D
C C
B B
A A
Title 
Size Document Number R e v 
Date: Sheet 
o f 
Honey_Badger_uServer 1B
CPU GND 1/2
A3
20 56Tuesday, January 20, 2015
Wiwynn Incorporated
http://www.wiwynn.com
8F, 90, Sec.1, Xintai 5th Rd., Xizhi Dist.,
New Taipei City 22102, Taiwan (R.O.C.)
Title 
Size Document Number R e v 
Date: Sheet 
o f 
Honey_Badger_uServer 1B
CPU GND 1/2
A3
20 56Tuesday, January 20, 2015
Wiwynn Incorporated
http://www.wiwynn.com
8F, 90, Sec.1, Xintai 5th Rd., Xizhi Dist.,
New Taipei City 22102, Taiwan (R.O.C.)
Title 
Size Document Number R e v 
Date: Sheet 
o f 
Honey_Badger_uServer 1B
CPU GND 1/2
A3
20 56Tuesday, January 20, 2015
Wiwynn Incorporated
http://www.wiwynn.com
8F, 90, Sec.1, Xintai 5th Rd., Xizhi Dist.,
New Taipei City 22102, Taiwan (R.O.C.)
AVOTON 
10 OF 12 U13J
AVOTON-GP
VSSR2
VSSR4
VSSR5
VSSR12
VSSR30
VSSR38
VSSR52
VSSR56
VSSR62
VSST18
VSST20
VSST21
VSST23
VSST28
VSST29
VSST31
VSST34
VSST36
VSST5
VSST41
VSST42
VSST47
VSST52
VSST56
VSST62
VSSU9
VSSU14
VSSU62
VSSU63
VSSU65
VSSV5
VSSV32
VSSV36
VSSV42
VSSV44
VSSW4
VSSW11
VSSW16
VSSW17
VSSW19
VSSW32
VSSW36
VSSW39
VSSW42
VSSW48
VSSW53
VSSW57
VSSW62
VSSY5
VSSY8
VSSY13
VSSY17
VSSY19
VSSY48
VSSY51
VSSY56
VSSY60
VSSAA3
VSSAA5
VSSAA23
VSSAA25
VSSAA26
VSSAA28
VSSAA29
VSSAA31
VSSAA36
VSSAA42
VSSAA44
VSSAA62
VSSAA64
VSS AA66
VSS AB1
VSS AB5
VSS AB20
VSS AC12
VSS AC18
VSS AC20
VSS AC21
VSS AC23
VSS AC28
VSS AC29
VSS AC31
VSS AC32
VSS AC34
VSS AC36
VSS AC46
VSS AC50
VSS AC55
VSS AC59
VSS AD2
VSS AD4
VSS AD5
VSS AD9
VSS AD14
VSS AD17
VSS AD18
VSS AD20
VSS AD34
VSS AD41
VSS AD46
VSS AD47
VSS AD52
VSS AD56
VSS AD62
VSS AE47
VSS AE64
VSS AF28
VSS AF44
VSS AF62
VSS AG5
VSS AG10
VSS AG16
VSS AG23
VSS AG25
VSS AG26
VSS AG28
VSS AG34
VSS AG41
VSS AG44
VSS AG48
VSS AG53
VSS AG57
VSS AG63
VSS AG64
VSS AG66
VSS AH11
VSS AH17
VSS AH53
VSS AH57
VSS AH62
VSS AJ28
VSS AJ32
VSS AJ44
VSS AJ46
VSS AJ47
VSS AK3
VSS AK5
VSS AK62
VSS AK64
VSS AK66
AVOTON 
9 OF 12 U13I
AVOTON-GP
VSSA5
VSSA9
VSSA12
VSSA15
VSSA18
VSSA24
VSSA30
VSSA33
VSSA45
VSSA48
VSSA51
VSSA57
VSSA59
VSSA61
VSSA62
VSSA64
VSSA66
VSSB10
VSSB26
VSSB41
VSSB55
VSSC3
VSSC6
VSSC18
VSSC33
VSSC45
VSSC49
VSSC51
VSSC58
VSSC64
VSSC66
VSSD6
VSSD10
VSSD26
VSSD33
VSSD41
VSSD42
VSSD51
VSSD55
VSSD59
VSSE1
VSSE3
VSSE10
VSSE13
VSSE14
VSSE16
VSSE18
VSSE19
VSSE21
VSSE22
VSSE23
VSSE25
VSSE27
VSSE28
VSSE30
VSSE31
VSSE34
VSSE36
VSSE37
VSSE39
VSSE40
VSSE41
VSSE43
VSSE45
VSSE46
VSSE48
VSSE49
VSSE50
VSSE52
VSSE54
VSS E55
VSS E59
VSS E61
VSS E64
VSS E66
VSS F1
VSS F4
VSS F5
VSS F63
VSS F66
VSS G32
VSS G34
VSS G41
VSS G48
VSS G56
VSS G59
VSS H1
VSS H34
VSS H37
VSS H38
VSS H41
VSS H44
VSS H46
VSS H52
VSS H54
VSS H56
VSS H58
VSS H59
VSS H66
VSS J29
VSS J63
VSS J64
VSS J66
VSS K1
VSS K32
VSS K34
VSS K42
VSS K50
VSS K62
VSS L30
VSS L34
VSS L48
VSS L50
VSS L60
VSS M5
VSS M37
VSS M38
VSS M44
VSS M46
VSS M52
VSS M54
VSS M56
VSS M57
VSS M59
VSS M60
VSS M66
VSS N1
VSS N5
VSS N10
VSS N34
VSS N48
VSS N50
VSS N62
VSS N63
VSS N65
VSS P29
VSS P32
VSS P34
VSS P37
VSS P44



5
5
4
4
3
3
2
2
1
1
D D
C C
B B
A A
Title 
Size Document Number R e v 
Date: Sheet 
o f 
Honey_Badger_uServer 1B
CPU GND 2/2
A3
21 56Tuesday, January 20, 2015
Wiwynn Incorporated
http://www.wiwynn.com
8F, 90, Sec.1, Xintai 5th Rd., Xizhi Dist.,
New Taipei City 22102, Taiwan (R.O.C.)
Title 
Size Document Number R e v 
Date: Sheet 
o f 
Honey_Badger_uServer 1B
CPU GND 2/2
A3
21 56Tuesday, January 20, 2015
Wiwynn Incorporated
http://www.wiwynn.com
8F, 90, Sec.1, Xintai 5th Rd., Xizhi Dist.,
New Taipei City 22102, Taiwan (R.O.C.)
Title 
Size Document Number R e v 
Date: Sheet 
o f 
Honey_Badger_uServer 1B
CPU GND 2/2
A3
21 56Tuesday, January 20, 2015
Wiwynn Incorporated
http://www.wiwynn.com
8F, 90, Sec.1, Xintai 5th Rd., Xizhi Dist.,
New Taipei City 22102, Taiwan (R.O.C.)
AVOTON 
11 OF 12 U13K
AVOTON-GP
VSSAL1
VSSAL5
VSSAL9
VSSAL14
VSSAL17
VSSAL18
VSSAL20
VSSAL29
VSSAL38
VSSAL42
VSSAL44
VSSAL50
VSSAL55
VSSAL59
VSSAM12
VSSAM18
VSSAM20
VSSAM21
VSSAM23
VSSAM44
VSSAM46
VSSAM50
VSSAM55
VSSAM59
VSSAN5
VSSAN47
VSSAN66
VSSAP5
VSSAP23
VSSAP25
VSSAP26
VSSAP28
VSSAP29
VSSAP31
VSSAP32
VSSAP34
VSSAP36
VSSAP38
VSSAP39
VSSAP41
VSSAP42
VSSAP44
VSSAP46
VSSAP64
VSSAR8
VSSAR13
VSSAR17
VSSAR19
VSSAR50
VSSAR56
VSSAR60
VSSAR62
VSSAT5
VSSAT11
VSSAT16
VSSAT17
VSSAT19
VSSAT44
VSSAT53
VSSAT57
VSSAT64
VSSAT66
VSSAU4
VSSAU62
VSSAV2
VSSAV4
VSSAV5
VSSAW5
VSSAW9
VSSAW14
VSS AW19
VSS AW23
VSS AW25
VSS AW26
VSS AW28
VSS AW30
VSS AW31
VSS AW32
VSS AW34
VSS AW46
VSS AW47
VSS AW49
VSS AW50
VSS AW52
VSS AW55
VSS AW59
VSS AY5
VSS AY12
VSS AY38
VSS AY45
VSS AY52
VSS AY55
VSS AY62
VSS BA17
VSS BA29
VSS BA34
VSS BA42
VSS BA49
VSS BB17
VSS BB34
VSS BB5
VSS BB53
VSS BB54
VSS BB56
VSS BB57
VSS BB62
VSS BB65
VSS BB66
VSS BC5
VSS BC30
VSS BC37
VSS BC46
VSS BD32
VSS BD34
VSS BD38
VSS BD41
VSS BD45
VSS BD50
VSS BD53
VSS BD59
VSS BD60
VSS BD62
VSS BD63
VSS BD65
VSS BE5
VSS BE32
VSS BE42
VSS BE49
VSS BE57
VSS BE66
VSS BF1
VSS BF3
VSS BF4
VSS BF29
VSS BF62
VSS BG1
VSS BG32
VSS BG37
VSS BG46
VSS BG54
AVOTON 
12 OF 12 U13L
AVOTON-GP
VSSBG63
VSSBG66
VSSBH32
VSSBH34
VSSBH41
VSSBH50
VSSBH60
VSSBH62
VSSBJ1
VSSBJ66
VSSBK1
VSSBK8
VSSBK10
VSSBK15
VSSBK17
VSSBK18
VSSBK19
VSSBK21
VSSBK22
VSSBK24
VSSBK26
VSSBK27
VSSBK28
VSSBK30
VSSBK31
VSSBK36
VSSBK37
VSSBK39
VSSBK42
VSSBK44
VSSBK45
VSSBK46
VSSBK48
VSSBK49
VSSBK51
VSSBK53
VSSBK56
VSSBK57
VSSBK58
VSSBK64
VSSBK66
VSS BL14
VSS BL19
VSS BL25
VSS BL30
VSS BL34
VSS BL37
VSS BL43
VSS BM1
VSS BM3
VSS BM5
VSS BM22
VSS BM45
VSS BM61
VSS BM62
VSS BM64
VSS BM66
VSS BN14
VSS BN30
VSS BN37
VSS BP1
VSS BP3
VSS BP5
VSS BP10
VSS BP13
VSS BP22
VSS BP31
VSS BP37
VSS BP40
VSS BP46
VSS BP52
VSS BP55
VSS BP58
VSS BP59
VSS BP61
VSS BP62
VSS BP64
VSS BP66
VSSA_USB AU44
VSSA_USB AW44



5
5
4
4
3
3
2
2
1
1
D D
C C
B B
A A
CPU_THERMTRIP#
H_THERMTRIP_N_R
CPU_THERMTRIP_LVC#
PROCESSOR_HOT_LVC#
H_PROCESSOR_HOT_N_R
PROCESSOR_HOT#
MEMORY_HOT_N_LV_B1
MEMORY_CPU_HOT#
MEMORY_HOT_LV_E1#
SMBUS_PECI_SW_EN
SMBUS_PECI_R_DATA
SMB_PECI_LV_R_CLK SMBUS_PECI_R_CLK
SMB_PECI_LV_R_DATA
DDR3_DRAM_PWROK
CLK_GEN_OUT_R
CLK_GEN_OUT
CLK_GEN_INA_PG
MEMORY_HOT_N_LV_B2
MEMORY_HOT_LV_E2#
MEMORY_FPGA_HOT#
SMBUS_SW_INV_D
SMB_HOST_LV_R_DATA
SMBUS_HOST_R_DATA
SMBUS_HOST_R_CLK
FPGA_SMB_HOST_R_CLK
FPGA_SMB_HOST_R_DATA
SMB_HOST_LV_R_CLK
P1V0
P3V3_STBY
P3V3_STBY
P1V0
P1V0
P1V0P3V3_STBY
P1V0
P1V0
PV_VDDR
P3V3_STBY
P3V3_STBY
P3V3
P3V3_STBY
P1V0
P3V3
P3V3
P3V3_STBY
P3V3_STBYP3V3_STBY
PV_VDDR
CPU_THERMTRIP#15
CPU_THERMTRIP_LVC# 38
PROCESSOR_HOT#15
PROCESSOR_HOT_LVC# 38
MEMORY_HOT_LV_R#26,27,28,29
MEMORY_CPU_HOT# 15
CLK_GEN_PG31,32,46,53
PWRGD_DDR3_VCCA 11,12
M_DRAM_PWROK 11,12
PMU_SLP_S45#15,16,38,51
SMBUS_PECI_CLK 15,16
SMBUS_PECI_DATA15,16 SMB_PECI_LV_DATA 38
SMB_PECI_LV_CLK38
PWRGD_PVDDR_PG51
CORE_PWROK 15,24
MEMORY_FPGA_HOT# 38
SMBUS_SW_EN15,16
FPGA_SMB_HOST_DATA 38
FPGA_SMB_HOST_CLK 38
SMB_HOST_LV_DATA26,27,28,29,30,31,35
SMBUS_HOST_DATA 15,16,24,32
SMBUS_HOST_CLK 15,16,24,32
SMB_HOST_LV_CLK26,27,28,29,30,31,35
SMBUS_SW_EN15,16
Title 
Size Document Number R ev 
Date: Sheet 
o f 
Honey_Badger_uServer 1B
CPU LEVEL SHIFT
Custom
22 56Tuesday, January 20, 2015
Wiwynn Incorporated
http://www.wiwynn.com
8F, 90, Sec.1, Xintai 5th Rd., Xizhi Dist.,
New Taipei City 22102, Taiwan (R.O.C.)
Title 
Size Document Number R ev 
Date: Sheet 
o f 
Honey_Badger_uServer 1B
CPU LEVEL SHIFT
Custom
22 56Tuesday, January 20, 2015
Wiwynn Incorporated
http://www.wiwynn.com
8F, 90, Sec.1, Xintai 5th Rd., Xizhi Dist.,
New Taipei City 22102, Taiwan (R.O.C.)
Title 
Size Document Number R ev 
Date: Sheet 
o f 
Honey_Badger_uServer 1B
CPU LEVEL SHIFT
Custom
22 56Tuesday, January 20, 2015
Wiwynn Incorporated
http://www.wiwynn.com
8F, 90, Sec.1, Xintai 5th Rd., Xizhi Dist.,
New Taipei City 22102, Taiwan (R.O.C.)
C5
SC2D2U10V2KX-GP
1 2
R276
1KR2F-3-GP
1 2
R61
0R2J-2-GP
1 2
Q12
MMBT3904TT1G-GP
C
B
E
R460
0R2J-2-GP
12
R15
0R2J-2-GP1 2
Q2
MMBT3904TT1G-GP
C
B
E
U9
2N7002DW-7F-GP
1
2
3 4
5
6
R33
1KR2F-3-GP
1 2
R390R2J-2-GP 1 2
Q11
MMBT3904TT1G-GP
C
B
E
R275
1KR2F-3-GP
1 2
R10
3K3R3F-GP
1 2
R34
49D9R2F-GP
1 2
C6
SCD1U10V2KX-5GP 
1 2
R498
4K7R2F-GP
1 2
R40 0R2J-2-GP12
R4730R2J-2-GP 12
U4
SN74LVC1G07DCKRG4-2-GP
GND3 A2 NC#11 VCC 5
Y 4
R50
0R2J-2-GP
12
U33
TS5A23157DGSR-GP
IN11
NO1 2
GND 3
NO2 4IN25
COM26
NC2 7V+8 NC1 9
COM110
R62
0R2J-2-GP
1 2
R49
0R2J-2-GP
12
R342
1KR2F-3-GP
12
R266
240R3-GP
1 2
R13
1KR2F-3-GP
1 2 Q1
MMBT3904TT1G-GP
C
B
E
R499
4K7R2F-GP
1 2
U3
2N7002DW-7F-GP
1
2
34
5
6U2
SN74LVC1G14DCKR-GP
NC#11
A2
GND3 Y 4
VCC 5
R19
1KR2F-3-GP
NOPOP
1 2
R17
20KR2F-L-GP
1 2
C8
SCD1U10V2KX-5GP
1 2
R260
240R3-GP
1 2
C15
SCD1U10V2KX-5GP
1 2
R4760R2J-2-GP 12
C72
SCD1U10V2KX-5GP
1 2
R18
150KR2F-L-GP
1 2
R360
1KR2F-3-GP
1 2
R356
1KR2F-3-GP
1 2
C7
SCD1U10V2KX-5GP
NOPOP
1 2
R262 0R2J-2-GP1 2
R360R2J-2-GP 1 2
Q16
2N7002A-7-GP
G
SD
R347
1KR2F-3-GP
NOPOP
12
R16
33R2F-3-GP
12
R280
1KR2F-3-GP
1 2
R35 0R2J-2-GP12
R263
330R2F-GP
1 2
R465
4K7R2F-GP
1 2
R32
1KR2F-3-GP
1 2
R14
1KR2F-3-GP
1 2



5
5
4
4
3
3
2
2
1
1
D D
C C
B B
A A
YELLOW LED 
Heatsink holder 
Power Status LED 
YELLOW LED 
GREEN/YELLOW LED 
Diagnostics LED 
CPU BEEP LED 
RTC BATTERY CIRCUIT 
BLUE LED 
BEEP_LEDBEEP_LED_D
CPU_BEEP_LED
DYMMY_NET1 DYMMY_NET2
PWR_STATUS_LED
CPU_DIAG_LED_R
PWR_STATUS_LED_EN
SRTCRST_BUF_IN#
P3V0_BAT P3V0_BAT_R
DIAG_LEDCPU_DIAG_LED_D
PWR_STATUS_LED_D
SRTCRST_BUF_IN#
P3V3
P12V
P3V3_STBY
P3V3
P3V3
P3V3_RTC
P3V3_STBY
SMB_CLK1_SPKR15,16
CPU_DIAG_LED14
SRTCRST# 15
Title 
Size Document Number R e v 
Date: Sheet 
o f 
Honey_Badger_uServer 1B
023 CPU INDICATOR LED
A3
23 56Tuesday, January 20, 2015
Wiwynn Incorporated
http://www.wiwynn.com
8F, 90, Sec.1, Xintai 5th Rd., Xizhi Dist.,
New Taipei City 22102, Taiwan (R.O.C.)
Title 
Size Document Number R e v 
Date: Sheet 
o f 
Honey_Badger_uServer 1B
023 CPU INDICATOR LED
A3
23 56Tuesday, January 20, 2015
Wiwynn Incorporated
http://www.wiwynn.com
8F, 90, Sec.1, Xintai 5th Rd., Xizhi Dist.,
New Taipei City 22102, Taiwan (R.O.C.)
Title 
Size Document Number R e v 
Date: Sheet 
o f 
Honey_Badger_uServer 1B
023 CPU INDICATOR LED
A3
23 56Tuesday, January 20, 2015
Wiwynn Incorporated
http://www.wiwynn.com
8F, 90, Sec.1, Xintai 5th Rd., Xizhi Dist.,
New Taipei City 22102, Taiwan (R.O.C.)
C82
SCD1U10V2KX-5GP
1 2
R84
0R2J-2-GP
1 2
CN1
PIN-CON2-6-GP-U
1
2
CN7
HR-CON2-6-GP
NOPOP
1
2
PTH1
PTH2
R404
0R2J-2-GP
1 2
R402
1KR2F-3-GP
1 2
R335
11KR2F-L-GP
1 2
Q5
2N7002A-7-GP
G
SD
LED17
LED-YG-51-GP
AK
CN2
PIN-CON2-6-GP-U
1
2
LED14
LED-Y-11-GP
1 2
LED1
LED-B-36-GP
12
D1
BAT54C-7-F-3-GP
1
2
3
R405
220KR2F-GP
1 2
R85
300R2F-GP
1 2
R410
10KR2F-2-GP
1 2
Q13
2N7002A-7-GP
G
SD
C322
SC22U6D3V5MX-2GP
NOPOP
1 2
U45
SNLVC1G17DCKR-GP
NC#11
A2
GND3 Y 4
VCC 5
C191
SC2D2U10V2KX-GP
1 2
Q14
2N7002A-7-GP
G
SD
R1
1KR5F-1-GP
1 2
R400
300R2F-GP
1 2



5
5
4
4
3
3
2
2
1
1
D D
C C
B B
A A
XDP_SOC_CPU_TCK
VCC_OBS_CD
XDP_P60
XDP_PWRBTN_R#
XDP_RST_BTN_R#
SMB_XDP_DATA_R
SMB_XDP_CLK_R
XDP_CPU_PRDY#
XDP_RSMRST_R#
TDI_56
XDP_CPU_PREQ#
TP_XDP_DFX_PORT_CLK1
XDP_PWRGD_IN
XDP_SOC_CPU_TCK
XDP_SOC_CPU_TRST#
XDP_SOC_CPU_TMS
XDP_SOC_CPU_TDI
TP_XDP0_TCK1
XDP_SOC_CPU_TDO
XDP_CPU_R_RESET#
XDP_DFX_PORT_R_CLK1
XDP_DFX_PORT_R_CLK0
XDP_RST_BTN_R#
XDP_CPU_R_TDO
XDP_RTEST#
XDP_RTEST#
P3V3_RTC
P1V0
P3V3_CPU
P1V0_STBY
P1V0
P1V0
P3V3
P1V0_STBY P1V0_STBY
P3V3_STBY
XDP_CPU_PRDY#15
XDP_SOC_CPU_TCK15,36
CLK_100M_XDP_R_DP 31
CLK_100M_XDP_R_DN 31
XDP_SOC_CPU_TDO 15,36
XDP_SOC_CPU_TRST# 15,36
XDP_SOC_CPU_TDI 15,36
XDP_SOC_CPU_TMS 15,36
XDP_CPU_RESET# 15
XDP_CPU_PREQ#15 XDP_DFX_PORT_CLK0 14
XDP_DFX_PORT_CLK1 14
XDP_PWRBTN#53
XDP_DFX_PORT014
XDP_DFX_PORT114
XDP_DFX_PORT214
XDP_DFX_PORT314
XDP_DFX_PORT414
XDP_DFX_PORT514
XDP_DFX_PORT614
XDP_DFX_PORT714
XDP_DFX_PORT8 14
XDP_DFX_PORT9 14
XDP_DFX_PORT10 14
XDP_DFX_PORT11 14
XDP_DFX_PORT12 14
XDP_DFX_PORT13 14
XDP_DFX_PORT14 14
XDP_DFX_PORT15 14CPU_RSMRST#15,16,35,37,39,46
CORE_PWROK15,22
SMBUS_HOST_DATA15,16,22,32
SMBUS_HOST_CLK15,16,22,32
XDP_RST_BTN_R# 53
XDP_BUF_RTEST# 15
Title 
Size Document Number R e v 
Date: Sheet 
o f 
Honey_Badger_uServer 1B
CPU XDP CONN
A3
24 56Tuesday, January 20, 2015
Wiwynn Incorporated
http://www.wiwynn.com
8F, 90, Sec.1, Xintai 5th Rd., Xizhi Dist.,
New Taipei City 22102, Taiwan (R.O.C.)
Title 
Size Document Number R e v 
Date: Sheet 
o f 
Honey_Badger_uServer 1B
CPU XDP CONN
A3
24 56Tuesday, January 20, 2015
Wiwynn Incorporated
http://www.wiwynn.com
8F, 90, Sec.1, Xintai 5th Rd., Xizhi Dist.,
New Taipei City 22102, Taiwan (R.O.C.)
Title 
Size Document Number R e v 
Date: Sheet 
o f 
Honey_Badger_uServer 1B
CPU XDP CONN
A3
24 56Tuesday, January 20, 2015
Wiwynn Incorporated
http://www.wiwynn.com
8F, 90, Sec.1, Xintai 5th Rd., Xizhi Dist.,
New Taipei City 22102, Taiwan (R.O.C.)
C314
SCD1U10V2KX-5GP
1 2
R472 0R2J-2-GP1 2
R277
51R2F-2-GP
1 2
R274
1KR2F-3-GP
1 2
R249 0R2J-2-GP1 2
R491
51R2F-2-GP
NOPOP
1 2
C114
SC1U10V2KX-1GP
1 2
R265 0R2J-2-GP1 2
R270
51R2F-2-GP
1 2
R241
1KR2F-3-GP
1 2
R245100R3F-1-GP 1 2
R247 51R2F-2-GP1 2
C120
SCD1U16V2KX-3GP
1 2
C116
SC10U6D3V3MX-GP
1 2
R264 0R2J-2-GP1 2
TP19TPAD28-1-GP-U 1
R2481KR2F-3-GP 1 2
R269
51R2F-2-GP
1 2
R242 0R2J-2-GP1 2
R488
51R2F-2-GP
NOPOP
1 2
R273
0R3J-0-U-GP
1 2
TP20TPAD28-1-GP-U 1
R487
51R2F-2-GP
NOPOP
1 2
R267
51R2F-2-GP
1 2
C115
SCD1U16V2KX-3GP
NOPOP
1 2 R271
0R3J-0-U-GP
1 2
R268 0R2J-2-GP1 2
R251
51R2F-2-GP
1 2
R489
51R2F-2-GP
NOPOP
1 2
CN4
SMC-CONN60A-GP
1
3
5
7
9
11
13
15
17
19
21
23
25
27
29
31
33
35
37
39
41
43
45
47
49
51
53
55
57
59
2
4
6
8
10
12
14
16
18
20
22
24
26
28
30
32
34
36
38
40
42
44
46
48
50
52
54
56
58
60
MH1
MH2
R2441KR2F-3-GP 1 2
R246 1KR2F-3-GP
NOPOP
1 2
R243
2K2R2F-GP 
1 2
R272 1KR3J-L1-GP1 2
R490
51R2F-2-GP
NOPOP
1 2
U46
SNLVC1G17DCKR-GP
NC#11
A2
GND3 Y 4
VCC 5



5
5
4
4
3
3
2
2
1
1
D D
C C
B B
A A
SPI ROM CIRCUIT 
SPI_CS0_N_M_1
SPI_MOSI_R_1
SPI_CPU_SCLK
SPI_HOLD#
SPI_CPU_MOSI
SPI_HOLD#SPI_MISO_R_1
SPI_WP_R_N_1
SPI_MISO_R_1
SPI_SCLK_R_1SPI_WP_R_N_1
SPI_CS0_N_M_1
SPI_CPU_MISO
SPI_CPU_CS0#
SPI_CPU_WP#
SPI_MOSI_R_1
SPI_SCLK_R_1
P3V3_CPU
P3V3_CPU
P3V3_CPU
SPI_CPU_MISO15
SPI_CPU_CS0#15,16
SPI_CPU_WP#15 SPI_CPU_SCLK 15
SPI_CPU_MOSI 15
Title 
Size Document Number Rev 
Date: Sheet o f 
Honey_Badger_uServer 1B
SPI REMOTE FLASH
A4
25 56Tuesday, January 20, 2015
Wiwynn Incorporated
http://www.wiwynn.com
8F, 90, Sec.1, Xintai 5th Rd., Xizhi Dist.,
New Taipei City 22102, Taiwan (R.O.C.)
Title 
Size Document Number Rev 
Date: Sheet o f 
Honey_Badger_uServer 1B
SPI REMOTE FLASH
A4
25 56Tuesday, January 20, 2015
Wiwynn Incorporated
http://www.wiwynn.com
8F, 90, Sec.1, Xintai 5th Rd., Xizhi Dist.,
New Taipei City 22102, Taiwan (R.O.C.)
Title 
Size Document Number Rev 
Date: Sheet o f 
Honey_Badger_uServer 1B
SPI REMOTE FLASH
A4
25 56Tuesday, January 20, 2015
Wiwynn Incorporated
http://www.wiwynn.com
8F, 90, Sec.1, Xintai 5th Rd., Xizhi Dist.,
New Taipei City 22102, Taiwan (R.O.C.)
R98
2K2R2F-GP
1 2
R110 33R2F-3-GP1 2 R109 33R2F-3-GP1 2
R105
4K7R2F-GP
12
SKT1
SKT-G6179T010-001-GP
1
2
3
4 5
6
7
8
R116
2K2R2F-GP
1 2
R115 33R2F-3-GP1 2
U18
W25Q64FVSSIG-GP
CS#1
DO/IO12
WP#/IO23
GND4
VCC 8
HOLD#/IO3 7
CLK 6
DI/IO0 5
R106 33R2F-3-GP1 2
R101 33R2F-3-GP1 2
C121
SCD1U16V2KX-3GP
1 2



5
5
4
4
3
3
2
2
1
1
D D
C C
B B
A A
SMBus Address: 0xA0 (10100000) 
 
DDR3_M_A_VREF_CA
DDR3_M_A_VREF_CA
M_A_DQ2
M_A_DQ18
M_A_DQ34
M_A_DQ50
M_A_DQ3
M_A_DQ19
M_A_DQ35
M_A_DQ51
M_A_DQ4
M_A_DQ20
M_A_DQ36
M_A_DQ52
M_A_DQ5
M_A_DQ21
M_A_DQ37
M_A_DQ53
M_A_DQ6
M_A_DQ22
M_A_DQ38
M_A_DQ54
M_A_DQ7
M_A_DQ23
M_A_DQ39
M_A_DQ55
M_A_DQ8
M_A_DQ24
M_A_DQ40
M_A_DQ56
M_A_DQ9
M_A_DQ25
M_A_DQ41
M_A_DQ57
M_A_DQ10
M_A_DQ26
M_A_DQS_DP1
M_A_DQ42
M_A_DQ58
M_A_DQS_DN1
M_A_DQS_DP2
M_A_DQS_DN2
M_A_DQS_DP3
M_A_DQS_DN3
M_A_DQ11
M_A_DQ27
M_A_DQ43
M_A_DQ59
M_A_DQS_DP4
M_A_DQS_DN4
M_A_DQS_DP5
M_A_DQS_DN5
M_A_DQ12
M_A_DQ28
M_A_DQ44
M_A_DQ60
M_A_DQS_DP6
M_A_DQS_DN6
M_A_DQ13
M_A_DQ29
M_A_DQ45
M_A_DQ61
M_A_DQS_DP7
M_A_DQS_DN7
M_A_DQS_DP8
M_A_DQS_DN8
M_A_DQ14
M_A_DQ30
M_A_DQ46
M_A_DQ62
M_A_DQ15
M_A_DQ31
M_A_DQ47
M_A_DQ63
M_A_DQS_DP0
M_A_DQS_DN0
M_A_DQ0M_A_RESET#
M_A_MA5
M_A_MA6
M_A_MA7
M_A_MA8
M_A_MA9
M_A_MA10
M_A_MA11
M_A_MA0
M_A_MA12
M_A_MA13
M_A_MA14
M_A_MA15
M_A_MA1
M_A_MA2
M_A_MA3
M_A_MA4
M_A_CK_DN1
M_A_CK_DP1
M_A_ODT1
M_A_CKE1
M_A_CS_N1
M_A_ECC1
M_A_ECC2
M_A_ECC3
M_A_ECC4
M_A_ECC5
M_A_ECC6
M_A_ECC7
M_A_ECC0
M_A_DQ16
M_A_WE#
M_A_RAS#
M_A_CAS#
M_A_DQ32
M_A_DQ48
M_A_CK_DP0
M_A_CK_DN0
M_A_ODT0
M_A_CKE0
M_A_BS1
M_A_BS0
M_A_BS2
M_A_CS_N0
M_A_DQ1
M_A_DQ17
M_A_DQ33
M_A_DQ49
SMB_M_A0_R_DATA
SMB_M_A0_R_CLK
MEMORY_HOT_LV_R#
CHA_0_SA1
CHA_0_SA0
CHA_0_SA1
CHA_0_SA0
PV_VDDR
PV_VDDR
PV_VTT_DDR_A
PV_VDDRP3V3_STBYPV_VTT_DDR_A
P3V3_STBYP3V3_STBY
DDR3_M_A_VREF_DQ0
PV_VDDR
M_A_ECC[7:0]11,27
M_A_DQ[63:0]11,27
M_A_MA[15:0]11,27
M_A_BS211,27
M_A_DQS_DN1 11,27
M_A_DQS_DP1 11,27
M_A_DQS_DP2 11,27
M_A_DQS_DN2 11,27
M_A_DQS_DN3 11,27
M_A_DQS_DP3 11,27
M_A_BS111,27
M_A_DQS_DP4 11,27
M_A_DQS_DN4 11,27
M_A_DQS_DN5 11,27
M_A_DQS_DP5 11,27
M_A_BS011,27
M_A_DQS_DP6 11,27
M_A_DQS_DN6 11,27
M_A_DQS_DN7 11,27
M_A_DQS_DP7 11,27
M_A_DQS_DP8 11,27
M_A_DQS_DN8 11,27
M_A_RESET#11,27
M_A_CK_DP111
M_A_CK_DN111
M_A_CKE111
M_A_CS_N111
M_A_ODT111
M_A_CK_DP011
M_A_CK_DN011
M_A_CKE011
M_A_CS_N011
M_A_DQS_DN0 11,27
M_A_ODT011
M_A_DQS_DP0 11,27
M_A_WE#11,27
M_A_CAS#11,27
M_A_RAS#11,27
SMB_HOST_LV_CLK22,27,28,29,30,31,35
SMB_HOST_LV_DATA22,27,28,29,30,31,35
MEMORY_HOT_LV_R#22,27,28,29
DDR3_M_A_VREF_CA 27
Title 
Size Document Number Rev 
Date: Sheet o f 
Honey_Badger_uServer 1B
CHA0 SO-DIMM SOCKET
A2
26 56Tuesday, January 20, 2015
Wiwynn Incorporated
http://www.wiwynn.com
8F, 90, Sec.1, Xintai 5th Rd., Xizhi Dist.,
New Taipei City 22102, Taiwan (R.O.C.)
Title 
Size Document Number Rev 
Date: Sheet o f 
Honey_Badger_uServer 1B
CHA0 SO-DIMM SOCKET
A2
26 56Tuesday, January 20, 2015
Wiwynn Incorporated
http://www.wiwynn.com
8F, 90, Sec.1, Xintai 5th Rd., Xizhi Dist.,
New Taipei City 22102, Taiwan (R.O.C.)
Title 
Size Document Number Rev 
Date: Sheet o f 
Honey_Badger_uServer 1B
CHA0 SO-DIMM SOCKET
A2
26 56Tuesday, January 20, 2015
Wiwynn Incorporated
http://www.wiwynn.com
8F, 90, Sec.1, Xintai 5th Rd., Xizhi Dist.,
New Taipei City 22102, Taiwan (R.O.C.)
C97
SC10U6D3V3MX-GP
1 2
C326
SCD1U16V2KX-3GP
1 2
C366
SC47U6D3V5MX-1-GP
1 2
2 OF 2 DIMM1B
DDR3-204P-142-COLAY-1-GP-U
VDD0132
VDD3123 VDD4116 VDD5115 VDD6110 VDD7109 VDD8102 VDD9101 VDD1094
VDD1385
VDD1131 VDD2124
VDD1193 VDD1286
VTT1203
VTT0204
GND45 2
GND44 3
GND43 8
GND42 9
GND41 14
GND40 17
GND39 20
GND38 23
GND37 26
GND36 29
GND35 32
GND34 35
GND33 38
GND32 41
GND31 46
GND30 47
GND29 52
GND28 53
GND27 58
GND26 61
GND25 64
GND24 67
GND23 70
GND22 73
GND21 78
GND20 79
GND19 137
GND18 138
GND17 143
GND16 146
GND15 149
GND14 152
GND13 155
GND12 158
GND11 163
GND10 164
GND9 169
GND8 170
GND7 175
GND6 178
GND5 181
GND4 184
GND3 187
GND2 190
GND1 195
GND0 196
VREF_CA84
VREF_DQ1
VDDSPD199
205 205
206 206
207207
208208
C105
SC10U6D3V3MX-GP
1 2
C101
SC1U10V2KX-1GP
1 2
C327
SCD1U16V2KX-3GP
1 2
R2360R2J-2-GP 12
C324
SCD1U16V2KX-3GP
1 2
C352
SC1U6D3V3KX-2GP
1 2
R227
4K7R2F-GP
NOPOP
1 2
R237
100R2F-L1-GP-U
1 2
C106
SC10U6D3V3MX-GP
1 2
C363
SC47U6D3V5MX-1-GP
1 2
R233
100R2F-L1-GP-U
1 2
R228
4K7R2F-GP
1 2
R231
4K7R2F-GP
NOPOP
1 2
C111
SC10U6D3V3MX-GP
1 2
C107
SCD1U16V2KX-3GP
1 2
C109
SCD1U16V2KX-3GP
1 2
C364
SC47U6D3V5MX-1-GP
1 2
R232
4K7R2F-GP
1 2
C112
SC10U6D3V3MX-GP
1 2
C325
SCD1U16V2KX-3GP
1 2
C365
SC47U6D3V5MX-1-GP
1 2
C102
SC1U6D3V2KX-GP
1 2
R2380R2J-2-GP 12
1 OF 2 DIMM1A
DDR3-204P-142-COLAY-1-GP-U
A1588
A1490
A13130
A1295
A1196
A10117
A992
A897
A798
A6100
A599
A4104
A3103
A2106
A1105
A0107
BA0119 BA1108
DQ0 5DQ1 7DQ2 13DQ3 15DQ4 4DQ5 6DQ6 16DQ7 18DQ8 19DQ9 21DQ10 31DQ11 33DQ12 22DQ13 24DQ14 34DQ15 36DQ16 37DQ17 39DQ18 49DQ19 51DQ20 40DQ21 42DQ22 48DQ23 50DQ24 55DQ25 57DQ26 63DQ27 65DQ28 54DQ29 56DQ30 66DQ31 68DQ32 133DQ33 135DQ34 145DQ35 147DQ36 134DQ37 136DQ38 142DQ39 144DQ40 151DQ41 153DQ42 159DQ43 161DQ44 148DQ45 150DQ46 160DQ47 162DQ48 165DQ49 167DQ50 177DQ51 179DQ52 166DQ53 168DQ54 174DQ55 176DQ56 183DQ57 185DQ58 191DQ59 193DQ60 180DQ61 182DQ62 192DQ63 194
DQS0# 10DQS1# 25DQS2# 43DQS3# 60DQS4# 139DQS5# 154DQS6# 171DQS7# 186
DQS0 12DQS1 27DQS2 45DQS3 62DQS4 141DQS5 156DQS6 173DQS7 188
ODT0126 ODT1128
NP1NP1
NP2NP2
RAS#122
WE#121 CAS#125
CKE087 CKE189
DM011 DM128 DM244 DM359 DM4140 DM5157 DM6172 DM7189
SDA200
SCL202
SA0197 SA1201
S1#129 S2#120 S3#118
RESET#30
EVENT#198
BA291
CK1#114
CK1112
CK0#113
CK0111
DQS8 77
DQS8# 75
S0#127
CB782
CB680
CB574
CB472
CB383
CB281
CB171
CB069
DM876



5
5
4
4
3
3
2
2
1
1
D D
C C
B B
A A
SMBus Address: 0xA2 (10100010) 
 
DDR3_M_A_VREF_CA
M_A_DQS_DP1
M_A_DQS_DN1
M_A_DQS_DP2
M_A_DQS_DN2
M_A_DQS_DP3
M_A_DQS_DN3
M_A_DQS_DP4
M_A_DQS_DN4
M_A_DQS_DP5
M_A_DQS_DN5
M_A_DQS_DP6
M_A_DQS_DN6
M_A_DQS_DP7
M_A_DQS_DN7
M_A_DQS_DP8
M_A_DQS_DN8
M_A_DQS_DP0
M_A_DQS_DN0
M_A_MA5
M_A_MA6
M_A_MA7
M_A_MA8
M_A_MA9
M_A_MA10
M_A_MA11
M_A_MA0
M_A_MA12
M_A_MA13
M_A_MA14
M_A_MA15
M_A_MA1
M_A_MA2
M_A_MA3
M_A_MA4
M_A_CK_DN3
M_A_CK_DP3
M_A_ODT3
M_A_CKE3
M_A_CS_N3
M_A_CK_DP2
M_A_CK_DN2
M_A_ODT2
M_A_CKE2
M_A_BS1
M_A_BS0
M_A_BS2
M_A_CS_N2
SMB_M_A1_R_DATA
SMB_M_A1_R_CLK
MEMORY_HOT_LV_R#
CHA_1_SA1
CHA_1_SA0
M_A_RESET#
M_A_WE#
M_A_RAS#
M_A_CAS#
CHA_1_SA1
CHA_1_SA0
M_A_DQ56
M_A_DQ58
M_A_DQ60
M_A_DQ62
M_A_DQ57
M_A_DQ59
M_A_DQ61
M_A_DQ63
M_A_DQ2
M_A_DQ18
M_A_DQ34
M_A_DQ50
M_A_DQ3
M_A_DQ19
M_A_DQ35
M_A_DQ51
M_A_DQ4
M_A_DQ20
M_A_DQ36
M_A_DQ52
M_A_DQ5
M_A_DQ21
M_A_DQ37
M_A_DQ53
M_A_DQ6
M_A_DQ22
M_A_DQ38
M_A_DQ7
M_A_DQ23
M_A_DQ39
M_A_DQ55
M_A_DQ8
M_A_DQ24
M_A_DQ40
M_A_DQ9
M_A_DQ25
M_A_DQ41
M_A_DQ54
M_A_DQ10
M_A_DQ26
M_A_DQ42
M_A_DQ11
M_A_DQ27
M_A_DQ43
M_A_DQ12
M_A_DQ28
M_A_DQ44
M_A_DQ13
M_A_DQ29
M_A_DQ45
M_A_DQ14
M_A_DQ30
M_A_DQ46
M_A_DQ15
M_A_DQ31
M_A_DQ47
M_A_DQ0
M_A_DQ16
M_A_DQ32
M_A_DQ48
M_A_DQ1
M_A_DQ17
M_A_DQ33
M_A_DQ49
M_A_ECC1
M_A_ECC2
M_A_ECC3
M_A_ECC4
M_A_ECC5
M_A_ECC6
M_A_ECC7
M_A_ECC0
PV_VDDR
PV_VTT_DDR_A
PV_VDDRP3V3_STBYPV_VTT_DDR_A
DDR3_M_A_VREF_DQ1
P3V3_STBYP3V3_STBY
PV_VDDR
M_A_ECC[7:0]11,26
M_A_DQ[63:0]11,26
M_A_MA[15:0]11,26
M_A_BS211,26
M_A_DQS_DN1 11,26
M_A_DQS_DP1 11,26
M_A_DQS_DP2 11,26
M_A_DQS_DN2 11,26
M_A_DQS_DN3 11,26
M_A_DQS_DP3 11,26
M_A_BS111,26
M_A_DQS_DP4 11,26
M_A_DQS_DN4 11,26
M_A_DQS_DN5 11,26
M_A_DQS_DP5 11,26
M_A_BS011,26
M_A_DQS_DP6 11,26
M_A_DQS_DN6 11,26
M_A_DQS_DN7 11,26
M_A_DQS_DP7 11,26
M_A_DQS_DP8 11,26
M_A_DQS_DN8 11,26
M_A_CK_DP311
M_A_CK_DN311
M_A_CKE311
M_A_CS_N311
M_A_ODT311
M_A_CK_DP211
M_A_CK_DN211
M_A_CKE211
M_A_CS_N211
M_A_DQS_DN0 11,26
M_A_ODT211
M_A_DQS_DP0 11,26
MEMORY_HOT_LV_R#22,26,28,29
DDR3_M_A_VREF_CA26
M_A_RESET#11,26
M_A_WE#11,26
M_A_CAS#11,26
M_A_RAS#11,26
SMB_HOST_LV_CLK22,26,28,29,30,31,35
SMB_HOST_LV_DATA22,26,28,29,30,31,35
Title 
Size Document Number Rev 
Date: Sheet o f 
Honey_Badger_uServer 1B
CHA1 SO-DIMM SOCKET
A2
27 56Tuesday, January 20, 2015
Wiwynn Incorporated
http://www.wiwynn.com
8F, 90, Sec.1, Xintai 5th Rd., Xizhi Dist.,
New Taipei City 22102, Taiwan (R.O.C.)
Title 
Size Document Number Rev 
Date: Sheet o f 
Honey_Badger_uServer 1B
CHA1 SO-DIMM SOCKET
A2
27 56Tuesday, January 20, 2015
Wiwynn Incorporated
http://www.wiwynn.com
8F, 90, Sec.1, Xintai 5th Rd., Xizhi Dist.,
New Taipei City 22102, Taiwan (R.O.C.)
Title 
Size Document Number Rev 
Date: Sheet o f 
Honey_Badger_uServer 1B
CHA1 SO-DIMM SOCKET
A2
27 56Tuesday, January 20, 2015
Wiwynn Incorporated
http://www.wiwynn.com
8F, 90, Sec.1, Xintai 5th Rd., Xizhi Dist.,
New Taipei City 22102, Taiwan (R.O.C.)
C108
SC10U6D3V3MX-GP
1 2
C328
SCD1U16V2KX-3GP
1 2
C110
SC10U6D3V3MX-GP
1 2
C359
SC47U6D3V5MX-1-GP
1 2
C104
SC10U6D3V3MX-GP
1 2
C360
SC47U6D3V5MX-1-GP
1 2
C103
SC10U6D3V3MX-GP
1 2
1 OF 2 DIMM2A
DDR3-204P-218-GP
A1588
A1490
A13130
A1295
A1196
A10117
A992
A897
A798
A6100
A599
A4104
A3103
A2106
A1105
A0107
BA0119 BA1108
DQ0 5DQ1 7DQ2 13DQ3 15DQ4 4DQ5 6DQ6 16DQ7 18DQ8 19DQ9 21DQ10 31DQ11 33DQ12 22DQ13 24DQ14 34DQ15 36DQ16 37DQ17 39DQ18 49DQ19 51DQ20 40DQ21 42DQ22 48DQ23 50DQ24 55DQ25 57DQ26 63DQ27 65DQ28 54DQ29 56DQ30 66DQ31 68DQ32 133DQ33 135DQ34 145DQ35 147DQ36 134DQ37 136DQ38 142DQ39 144DQ40 151DQ41 153DQ42 159DQ43 161DQ44 148DQ45 150DQ46 160DQ47 162DQ48 165DQ49 167DQ50 177DQ51 179DQ52 166DQ53 168DQ54 174DQ55 176DQ56 183DQ57 185DQ58 191DQ59 193DQ60 180DQ61 182DQ62 192DQ63 194
DQS0# 10DQS1# 25DQS2# 43DQS3# 60DQS4# 139DQS5# 154DQS6# 171DQS7# 186
DQS0 12DQS1 27DQS2 45DQS3 62DQS4 141DQS5 156DQS6 173DQS7 188
ODT0126 ODT1128
NP1NP1
NP2NP2
RAS#122
WE#121 CAS#125
CKE087 CKE189
DM011 DM128 DM244 DM359 DM4140 DM5157 DM6172 DM7189
SDA200
SCL202
SA0197 SA1201
S1#129 S2#120 S3#118
RESET#30
EVENT#198
BA291
CK1#114
CK1112
CK0#113
CK0111
DQS8 77
DQS8# 75
S0#127
CB782
CB680
CB574
CB472
CB383
CB281
CB171
CB069
DM876
C329
SCD1U16V2KX-3GP
1 2
C99
SC1U10V2KX-1GP
1 2
C100
SC10U6D3V3MX-GP
1 2
C98
SC1U6D3V2KX-GP
1 2
C353
SC1U6D3V3KX-2GP
1 2
C361
SC47U6D3V5MX-1-GP
1 2
C330
SCD1U16V2KX-3GP
1 2
R2250R2J-2-GP 12
C331
SCD1U16V2KX-3GP
1 2
R229
4K7R2F-GP
1 2
R235
4K7R2F-GP
NOPOP
1 2
C2
SCD1U16V2KX-3GP
1 2
R230
4K7R2F-GP
NOPOP
1 2
C362
SC47U6D3V5MX-1-GP
1 2
R234
4K7R2F-GP
1 2
2 OF 2 DIMM2B
DDR3-204P-218-GP
VDD0132
VDD3123 VDD4116 VDD5115 VDD6110 VDD7109 VDD8102 VDD9101 VDD1094
VDD1385
VDD1131 VDD2124
VDD1193 VDD1286
VTT1203
VTT0204
GND45 2
GND44 3
GND43 8
GND42 9
GND41 14
GND40 17
GND39 20
GND38 23
GND37 26
GND36 29
GND35 32
GND34 35
GND33 38
GND32 41
GND31 46
GND30 47
GND29 52
GND28 53
GND27 58
GND26 61
GND25 64
GND24 67
GND23 70
GND22 73
GND21 78
GND20 79
GND19 137
GND18 138
GND17 143
GND16 146
GND15 149
GND14 152
GND13 155
GND12 158
GND11 163
GND10 164
GND9 169
GND8 170
GND7 175
GND6 178
GND5 181
GND4 184
GND3 187
GND2 190
GND1 195
GND0 196
VREF_CA84
VREF_DQ1
VDDSPD199
205 205
206 206
R2260R2J-2-GP 12



5
5
4
4
3
3
2
2
1
1
D D
C C
B B
A A
SMBus Address: 0xA4 (10100100) 
 
DDR3_M_B_VREF_CA
DDR3_M_B_VREF_CA
M_B_DQ2
M_B_DQ18
M_B_DQ34
M_B_DQ50
M_B_DQ3
M_B_DQ19
M_B_DQ35
M_B_DQ51
M_B_DQ4
M_B_DQ20
M_B_DQ36
M_B_DQ52
M_B_DQ5
M_B_DQ21
M_B_DQ37
M_B_DQ53
M_B_DQ6
M_B_DQ22
M_B_DQ38
M_B_DQ54
M_B_DQ7
M_B_DQ23
M_B_DQ39
M_B_DQ55
M_B_DQ8
M_B_DQ24
M_B_DQ40
M_B_DQ56
M_B_DQ9
M_B_DQ25
M_B_DQ41
M_B_DQ57
M_B_DQ10
M_B_DQ26
M_B_DQS_DP1
M_B_DQ42
M_B_DQ58
M_B_DQS_DN1
M_B_DQS_DP2
M_B_DQS_DN2
M_B_DQS_DP3
M_B_DQS_DN3
M_B_DQ11
M_B_DQ27
M_B_DQ43
M_B_DQ59
M_B_DQS_DP4
M_B_DQS_DN4
M_B_DQS_DP5
M_B_DQS_DN5
M_B_DQ12
M_B_DQ28
M_B_DQ44
M_B_DQ60
M_B_DQS_DP6
M_B_DQS_DN6
M_B_DQ13
M_B_DQ29
M_B_DQ45
M_B_DQ61
M_B_DQS_DP7
M_B_DQS_DN7
M_B_DQS_DP8
M_B_DQS_DN8
M_B_DQ14
M_B_DQ30
M_B_DQ46
M_B_DQ62
M_B_DQ15
M_B_DQ31
M_B_DQ47
M_B_DQ63
M_B_DQS_DP0
M_B_DQS_DN0
M_B_DQ0
M_B_MA5
M_B_MA6
M_B_MA7
M_B_MA8
M_B_MA9
M_B_MA10
M_B_MA11
M_B_MA0
M_B_MA12
M_B_MA13
M_B_MA14
M_B_MA15
M_B_MA1
M_B_MA2
M_B_MA3
M_B_MA4
M_B_CK_DN1
M_B_CK_DP1
M_B_ODT1
M_B_CKE1
M_B_CS_N1
M_B_ECC1
M_B_ECC2
M_B_ECC3
M_B_ECC4
M_B_ECC5
M_B_ECC6
M_B_ECC7
M_B_ECC0
M_B_DQ16
M_B_DQ32
M_B_DQ48
M_B_CK_DP0
M_B_CK_DN0
M_B_ODT0
M_B_CKE0
M_B_BS1
M_B_BS0
M_B_BS2
M_B_CS_N0
M_B_DQ1
M_B_DQ17
M_B_DQ33
M_B_DQ49
SMB_M_B0_R_DATA
SMB_M_B0_R_CLK
MEMORY_HOT_LV_R#
CHB_0_SA0
CHB_0_SA1
M_B_RESET#
M_B_WE#
M_B_RAS#
M_B_CAS#
CHB_0_SA1
CHB_0_SA0
PV_VDDR
PV_VDDR
PV_VTT_DDR_B
PV_VDDRP3V3_STBYPV_VTT_DDR_B
DDR3_M_B_VREF_DQ0
P3V3_STBYP3V3_STBY
PV_VDDR
M_B_ECC[7:0]12,29
M_B_DQ[63:0]12,29
M_B_MA[15:0]12,29
M_B_BS212,29
M_B_DQS_DN1 12,29
M_B_DQS_DP1 12,29
M_B_DQS_DP2 12,29
M_B_DQS_DN2 12,29
M_B_DQS_DN3 12,29
M_B_DQS_DP3 12,29
M_B_BS112,29
M_B_DQS_DP4 12,29
M_B_DQS_DN4 12,29
M_B_DQS_DN5 12,29
M_B_DQS_DP5 12,29
M_B_BS012,29
M_B_DQS_DP6 12,29
M_B_DQS_DN6 12,29
M_B_DQS_DN7 12,29
M_B_DQS_DP7 12,29
M_B_DQS_DP8 12,29
M_B_DQS_DN8 12,29
M_B_CK_DP112
M_B_CK_DN112
M_B_CKE112
M_B_CS_N112
M_B_ODT112
M_B_CK_DP012
M_B_CK_DN012
M_B_CKE012
M_B_CS_N012
M_B_DQS_DN0 12,29
M_B_ODT012
M_B_DQS_DP0 12,29
MEMORY_HOT_LV_R#22,26,27,29
DDR3_M_B_VREF_CA 29
M_B_RESET#12,29
M_B_WE#12,29
M_B_CAS#12,29
M_B_RAS#12,29
SMB_HOST_LV_CLK22,26,27,29,30,31,35
SMB_HOST_LV_DATA22,26,27,29,30,31,35
Title 
Size Document Number Rev 
Date: Sheet o f 
Honey_Badger_uServer 1B
CHB0 SO-DIMM SOCKET
A2
28 56Tuesday, January 20, 2015
Wiwynn Incorporated
http://www.wiwynn.com
8F, 90, Sec.1, Xintai 5th Rd., Xizhi Dist.,
New Taipei City 22102, Taiwan (R.O.C.)
Title 
Size Document Number Rev 
Date: Sheet o f 
Honey_Badger_uServer 1B
CHB0 SO-DIMM SOCKET
A2
28 56Tuesday, January 20, 2015
Wiwynn Incorporated
http://www.wiwynn.com
8F, 90, Sec.1, Xintai 5th Rd., Xizhi Dist.,
New Taipei City 22102, Taiwan (R.O.C.)
Title 
Size Document Number Rev 
Date: Sheet o f 
Honey_Badger_uServer 1B
CHB0 SO-DIMM SOCKET
A2
28 56Tuesday, January 20, 2015
Wiwynn Incorporated
http://www.wiwynn.com
8F, 90, Sec.1, Xintai 5th Rd., Xizhi Dist.,
New Taipei City 22102, Taiwan (R.O.C.)
C332
SCD1U16V2KX-3GP
1 2
C293
SC10U6D3V3MX-GP
1 2
C333
SCD1U16V2KX-3GP
1 2
R197
4K7R2F-GP
NOPOP
1 2
R3840R2J-2-GP 12
C367
SC47U6D3V5MX-1-GP
1 2
1 OF 2 DIMM3A
DDR3-204P-142-COLAY-1-GP-U
A1588
A1490
A13130
A1295
A1196
A10117
A992
A897
A798
A6100
A599
A4104
A3103
A2106
A1105
A0107
BA0119 BA1108
DQ0 5DQ1 7DQ2 13DQ3 15DQ4 4DQ5 6DQ6 16DQ7 18DQ8 19DQ9 21DQ10 31DQ11 33DQ12 22DQ13 24DQ14 34DQ15 36DQ16 37DQ17 39DQ18 49DQ19 51DQ20 40DQ21 42DQ22 48DQ23 50DQ24 55DQ25 57DQ26 63DQ27 65DQ28 54DQ29 56DQ30 66DQ31 68DQ32 133DQ33 135DQ34 145DQ35 147DQ36 134DQ37 136DQ38 142DQ39 144DQ40 151DQ41 153DQ42 159DQ43 161DQ44 148DQ45 150DQ46 160DQ47 162DQ48 165DQ49 167DQ50 177DQ51 179DQ52 166DQ53 168DQ54 174DQ55 176DQ56 183DQ57 185DQ58 191DQ59 193DQ60 180DQ61 182DQ62 192DQ63 194
DQS0# 10DQS1# 25DQS2# 43DQS3# 60DQS4# 139DQS5# 154DQS6# 171DQS7# 186
DQS0 12DQS1 27DQS2 45DQS3 62DQS4 141DQS5 156DQS6 173DQS7 188
ODT0126 ODT1128
NP1NP1
NP2NP2
RAS#122
WE#121 CAS#125
CKE087 CKE189
DM011 DM128 DM244 DM359 DM4140 DM5157 DM6172 DM7189
SDA200
SCL202
SA0197 SA1201
S1#129 S2#120 S3#118
RESET#30
EVENT#198
BA291
CK1#114
CK1112
CK0#113
CK0111
DQS8 77
DQS8# 75
S0#127
CB782
CB680
CB574
CB472
CB383
CB281
CB171
CB069
DM876
C294
SCD1U16V2KX-3GP
1 2
C291
SC1U6D3V2KX-GP
1 2 C368
SC47U6D3V5MX-1-GP
1 2
C334
SCD1U16V2KX-3GP
1 2
C369
SC47U6D3V5MX-1-GP
1 2
R3830R2J-2-GP 12
C290
SC10U6D3V3MX-GP
1 2
2 OF 2 DIMM3B
DDR3-204P-142-COLAY-1-GP-U
VDD0132
VDD3123 VDD4116 VDD5115 VDD6110 VDD7109 VDD8102 VDD9101 VDD1094
VDD1385
VDD1131 VDD2124
VDD1193 VDD1286
VTT1203
VTT0204
GND45 2
GND44 3
GND43 8
GND42 9
GND41 14
GND40 17
GND39 20
GND38 23
GND37 26
GND36 29
GND35 32
GND34 35
GND33 38
GND32 41
GND31 46
GND30 47
GND29 52
GND28 53
GND27 58
GND26 61
GND25 64
GND24 67
GND23 70
GND22 73
GND21 78
GND20 79
GND19 137
GND18 138
GND17 143
GND16 146
GND15 149
GND14 152
GND13 155
GND12 158
GND11 163
GND10 164
GND9 169
GND8 170
GND7 175
GND6 178
GND5 181
GND4 184
GND3 187
GND2 190
GND1 195
GND0 196
VREF_CA84
VREF_DQ1
VDDSPD199
205 205
206 206
207207
208208
C354
SC1U6D3V3KX-2GP
1 2
R385
100R2F-L1-GP-U
1 2
C370
SC47U6D3V5MX-1-GP
1 2
C340
SCD1U16V2KX-3GP
1 2
C288
SC10U6D3V3MX-GP
1 2
C295
SCD1U16V2KX-3GP
1 2
R198
4K7R2F-GP
1 2
R196
4K7R2F-GP
NOPOP
1 2
C298
SC10U6D3V3MX-GP
1 2
R195
4K7R2F-GP
1 2 C299
SC1U10V2KX-1GP
1 2
R386
100R2F-L1-GP-U
1 2
C289
SC10U6D3V3MX-GP
1 2



5
5
4
4
3
3
2
2
1
1
D D
C C
B B
A A
SMBus Address: 0xA6 (10100110) 
 
DDR3_M_B_VREF_CA
M_B_DQS_DP1
M_B_DQS_DN1
M_B_DQS_DP2
M_B_DQS_DN2
M_B_DQS_DP3
M_B_DQS_DN3
M_B_DQS_DP4
M_B_DQS_DN4
M_B_DQS_DP5
M_B_DQS_DN5
M_B_DQS_DP6
M_B_DQS_DN6
M_B_DQS_DP7
M_B_DQS_DN7
M_B_DQS_DP8
M_B_DQS_DN8
M_B_DQS_DP0
M_B_DQS_DN0
M_B_MA5
M_B_MA6
M_B_MA7
M_B_MA8
M_B_MA9
M_B_MA10
M_B_MA11
M_B_MA0
M_B_MA12
M_B_MA13
M_B_MA14
M_B_MA15
M_B_MA1
M_B_MA2
M_B_MA3
M_B_MA4
M_B_CK_DN3
M_B_CK_DP3
M_B_ODT3
M_B_CKE3
M_B_CS_N3
M_B_CK_DP2
M_B_CK_DN2
M_B_ODT2
M_B_CKE2
M_B_BS1
M_B_BS0
M_B_BS2
M_B_CS_N2
SMB_M_B1_R_DATA
SMB_M_B1_R_CLK
MEMORY_HOT_LV_R#
CHB_1_SA1
CHB_1_SA0
CHB_1_SA0
CHB_1_SA1
M_B_RESET#
M_B_WE#
M_B_RAS#
M_B_CAS#
M_B_DQ7
M_B_DQ23
M_B_DQ39
M_B_DQ55
M_B_DQ8
M_B_DQ24
M_B_DQ40
M_B_DQ56
M_B_DQ9
M_B_DQ25
M_B_DQ41
M_B_DQ57
M_B_DQ10
M_B_DQ26
M_B_DQ42
M_B_DQ58
M_B_DQ11
M_B_DQ27
M_B_DQ43
M_B_DQ59
M_B_DQ12
M_B_DQ28
M_B_DQ44
M_B_DQ60
M_B_DQ13
M_B_DQ29
M_B_DQ45
M_B_DQ61
M_B_DQ14
M_B_DQ30
M_B_DQ46
M_B_DQ62
M_B_DQ15
M_B_DQ31
M_B_DQ47
M_B_DQ63
M_B_DQ0
M_B_DQ16
M_B_DQ32
M_B_DQ48
M_B_DQ1
M_B_DQ17
M_B_DQ33
M_B_DQ49
M_B_DQ2
M_B_DQ18
M_B_DQ34
M_B_DQ50
M_B_DQ3
M_B_DQ19
M_B_DQ35
M_B_DQ51
M_B_DQ4
M_B_DQ20
M_B_DQ36
M_B_DQ52
M_B_DQ5
M_B_DQ21
M_B_DQ37
M_B_DQ53
M_B_DQ6
M_B_DQ22
M_B_DQ38
M_B_DQ54
M_B_ECC1
M_B_ECC2
M_B_ECC3
M_B_ECC4
M_B_ECC5
M_B_ECC6
M_B_ECC7
M_B_ECC0
PV_VDDR
PV_VTT_DDR_B
PV_VDDRP3V3_STBYPV_VTT_DDR_B
P3V3_STBYP3V3_STBY
DDR3_M_B_VREF_DQ1
PV_VDDR
M_B_ECC[7:0]12,28
M_B_DQ[63:0]12,28
M_B_MA[15:0]12,28
M_B_BS212,28
M_B_DQS_DN1 12,28
M_B_DQS_DP1 12,28
M_B_DQS_DP2 12,28
M_B_DQS_DN2 12,28
M_B_DQS_DN3 12,28
M_B_DQS_DP3 12,28
M_B_BS112,28
M_B_DQS_DP4 12,28
M_B_DQS_DN4 12,28
M_B_DQS_DN5 12,28
M_B_DQS_DP5 12,28
M_B_BS012,28
M_B_DQS_DP6 12,28
M_B_DQS_DN6 12,28
M_B_DQS_DN7 12,28
M_B_DQS_DP7 12,28
M_B_DQS_DP8 12,28
M_B_DQS_DN8 12,28
M_B_CK_DP312
M_B_CK_DN312
M_B_CKE312
M_B_CS_N312
M_B_ODT312
M_B_CK_DP212
M_B_CK_DN212
M_B_CKE212
M_B_CS_N212
M_B_DQS_DN0 12,28
M_B_ODT212
M_B_DQS_DP0 12,28
MEMORY_HOT_LV_R#22,26,27,28
DDR3_M_B_VREF_CA28
M_B_RESET#12,28
M_B_WE#12,28
M_B_CAS#12,28
M_B_RAS#12,28
SMB_HOST_LV_CLK22,26,27,28,30,31,35
SMB_HOST_LV_DATA22,26,27,28,30,31,35
Title 
Size Document Number Rev 
Date: Sheet o f 
Honey_Badger_uServer 1B
CHB1 SO-DIMM SOCKET
A2
29 56Tuesday, January 20, 2015
Wiwynn Incorporated
http://www.wiwynn.com
8F, 90, Sec.1, Xintai 5th Rd., Xizhi Dist.,
New Taipei City 22102, Taiwan (R.O.C.)
Title 
Size Document Number Rev 
Date: Sheet o f 
Honey_Badger_uServer 1B
CHB1 SO-DIMM SOCKET
A2
29 56Tuesday, January 20, 2015
Wiwynn Incorporated
http://www.wiwynn.com
8F, 90, Sec.1, Xintai 5th Rd., Xizhi Dist.,
New Taipei City 22102, Taiwan (R.O.C.)
Title 
Size Document Number Rev 
Date: Sheet o f 
Honey_Badger_uServer 1B
CHB1 SO-DIMM SOCKET
A2
29 56Tuesday, January 20, 2015
Wiwynn Incorporated
http://www.wiwynn.com
8F, 90, Sec.1, Xintai 5th Rd., Xizhi Dist.,
New Taipei City 22102, Taiwan (R.O.C.)
C344
SCD1U16V2KX-3GP
1 2
1 OF 2 DIMM4A
DDR3-204P-218-GP
A1588
A1490
A13130
A1295
A1196
A10117
A992
A897
A798
A6100
A599
A4104
A3103
A2106
A1105
A0107
BA0119 BA1108
DQ0 5DQ1 7DQ2 13DQ3 15DQ4 4DQ5 6DQ6 16DQ7 18DQ8 19DQ9 21DQ10 31DQ11 33DQ12 22DQ13 24DQ14 34DQ15 36DQ16 37DQ17 39DQ18 49DQ19 51DQ20 40DQ21 42DQ22 48DQ23 50DQ24 55DQ25 57DQ26 63DQ27 65DQ28 54DQ29 56DQ30 66DQ31 68DQ32 133DQ33 135DQ34 145DQ35 147DQ36 134DQ37 136DQ38 142DQ39 144DQ40 151DQ41 153DQ42 159DQ43 161DQ44 148DQ45 150DQ46 160DQ47 162DQ48 165DQ49 167DQ50 177DQ51 179DQ52 166DQ53 168DQ54 174DQ55 176DQ56 183DQ57 185DQ58 191DQ59 193DQ60 180DQ61 182DQ62 192DQ63 194
DQS0# 10DQS1# 25DQS2# 43DQS3# 60DQS4# 139DQS5# 154DQS6# 171DQS7# 186
DQS0 12DQS1 27DQS2 45DQS3 62DQS4 141DQS5 156DQS6 173DQS7 188
ODT0126 ODT1128
NP1NP1
NP2NP2
RAS#122
WE#121 CAS#125
CKE087 CKE189
DM011 DM128 DM244 DM359 DM4140 DM5157 DM6172 DM7189
SDA200
SCL202
SA0197 SA1201
S1#129 S2#120 S3#118
RESET#30
EVENT#198
BA291
CK1#114
CK1112
CK0#113
CK0111
DQS8 77
DQS8# 75
S0#127
CB782
CB680
CB574
CB472
CB383
CB281
CB171
CB069
DM876
C371
SC47U6D3V5MX-1-GP
1 2
C301
SC10U6D3V3MX-GP
1 2
C297
SC1U10V2KX-1GP
1 2
R388
4K7R2F-GP
1 2
R390
4K7R2F-GP
1 2
C300
SC10U6D3V3MX-GP
1 2
C372
SC47U6D3V5MX-1-GP
1 2
C292
SC10U6D3V3MX-GP
1 2
C373
SC47U6D3V5MX-1-GP
1 2
C91
SC10U6D3V3MX-GP
1 2
C355
SC1U6D3V3KX-2GP
1 2
C341
SCD1U16V2KX-3GP
1 2
R3910R2J-2-GP 12
C374
SC47U6D3V5MX-1-GP
1 2
2 OF 2 DIMM4B
DDR3-204P-218-GP
VDD0132
VDD3123 VDD4116 VDD5115 VDD6110 VDD7109 VDD8102 VDD9101 VDD1094
VDD1385
VDD1131 VDD2124
VDD1193 VDD1286
VTT1203
VTT0204
GND45 2
GND44 3
GND43 8
GND42 9
GND41 14
GND40 17
GND39 20
GND38 23
GND37 26
GND36 29
GND35 32
GND34 35
GND33 38
GND32 41
GND31 46
GND30 47
GND29 52
GND28 53
GND27 58
GND26 61
GND25 64
GND24 67
GND23 70
GND22 73
GND21 78
GND20 79
GND19 137
GND18 138
GND17 143
GND16 146
GND15 149
GND14 152
GND13 155
GND12 158
GND11 163
GND10 164
GND9 169
GND8 170
GND7 175
GND6 178
GND5 181
GND4 184
GND3 187
GND2 190
GND1 195
GND0 196
VREF_CA84
VREF_DQ1
VDDSPD199
205 205
206 206
C87
SC1U6D3V2KX-GP
1 2
R389
4K7R2F-GP
NOPOP
1 2
C343
SCD1U16V2KX-3GP
1 2
C296
SCD1U16V2KX-3GP
1 2
C90
SC10U6D3V3MX-GP
1 2
C342
SCD1U16V2KX-3GP
1 2
R3920R2J-2-GP 12
R387
4K7R2F-GP
NOPOP
1 2



5
5
4
4
3
3
2
2
1
1
D D
C C
B B
A A
Slave Address: 5C 
PV_VDDR_VREF_B_FB
SMB_DPOT_CLK
PV_VDDR_VREF_A_FB
PV_VDDR_VREF_A
SMB_DPOT_DATA
PV_VDDR_VREF_B
PV_VDDR_VREF_RW
DDR3_M_A_VREF_DQ1
P3V3_STBY
PV_VDDR
P3V3_STBY
PV_VDDR
P3V3_STBY PV_VDDR
DDR3_M_B_VREF_DQ1
DDR3_M_B_VREF_DQ0
DDR3_M_A_VREF_DQ0
SMB_HOST_LV_CLK22,26,27,28,29,31,35
SMB_HOST_LV_DATA22,26,27,28,29,31,35
Title 
Size Document Number R e v 
Date: Sheet 
o f 
Honey_Badger_uServer 1B
DIMM VREF
A3
30 56Tuesday, January 20, 2015
Wiwynn Incorporated
http://www.wiwynn.com
8F, 90, Sec.1, Xintai 5th Rd., Xizhi Dist.,
New Taipei City 22102, Taiwan (R.O.C.)
Title 
Size Document Number R e v 
Date: Sheet 
o f 
Honey_Badger_uServer 1B
DIMM VREF
A3
30 56Tuesday, January 20, 2015
Wiwynn Incorporated
http://www.wiwynn.com
8F, 90, Sec.1, Xintai 5th Rd., Xizhi Dist.,
New Taipei City 22102, Taiwan (R.O.C.)
Title 
Size Document Number R e v 
Date: Sheet 
o f 
Honey_Badger_uServer 1B
DIMM VREF
A3
30 56Tuesday, January 20, 2015
Wiwynn Incorporated
http://www.wiwynn.com
8F, 90, Sec.1, Xintai 5th Rd., Xizhi Dist.,
New Taipei City 22102, Taiwan (R.O.C.)
U26
ISL90727WIE627Z-TK-2-GP
VDD1
GND2
SCL3 SDA 4RW 5RH 6
C92
SC1U6D3V2KX-GP
1 2
R218
0R2J-2-GP
1 2
R201
0R2J-2-GP
1 2
R203
100R2F-L1-GP-U
1 2
R202
2D2R2J-GP
1 2
R209
12K1R2F-L1-GP
1 2
R222
0R2J-2-GP
1 2
R217
0R2J-2-GP
1 2
U27
LMV321IDCKR-1-GP
1IN-3 GND2 1IN+1
OUT 4
VCC+ 5
R200
0R2J-2-GP
1 2
R220
100R2F-L1-GP-U
1 2
C94
SCD1U16V2KX-3GP
1 2
R208
12K1R2F-L1-GP
1 2
C95
SCD1U16V2KX-3GP
1 2
R204
100R2F-L1-GP-U
NOPOP
1 2
C96
SC1U6D3V2KX-GP
1 2
U23
LMV321IDCKR-1-GP
1IN-3 GND2 1IN+1
OUT 4
VCC+ 5
C93
SCD1U16V2KX-3GP
1 2
R221
2D2R2J-GP
1 2
R219
100R2F-L1-GP-U
NOPOP
1 2
R223
0R2J-2-GP
1 2



5
5
4
4
3
3
2
2
1
1
D D
C C
B B
A A
P3V3_CLK_XTAL
P3V3_CLK_PCI
P1V5_CLK_SCR_LVIO
P1V5_CLK_VDDDIF
P1V5_CLK_VDD_CORE
P3V3_CLK_VDD25
SMB_CLKGEN_R_DATA
SMB_CLKGEN_R_CLK
CLKGEN_PCI_STOP#
CLKGEN_VSEL_PCI
CLKGEN_DIF_STOP#
XTAL_CLK_GEN_IN XTAL_CLK_GEN_OUT
P1V5_CLK_VDD_CORE
P1V5_CLK_VDDDIF
P1V5_CLK_SCR_LVIO
P3V3_CLK_R_VDD25 P3V3_CLK_VDD25
P3V3_CLK_R_PCI P3V3_CLK_PCI
CLK_100M_XDP_R_DP
CLK_100M_XDP_R_DN
CLK_100M_CPU_HFHPLL_DP
CLK_100M_CPU_HFHPLL_DN
CLK_100M_CPU_MPLL0_DP
CLK_100M_CPU_MPLL0_DN
CLK_100M_CLKBUFF_DP
CLK_100M_CLKBUFF_DN
CLK_96M_CPU_USB_DP
CLK_96M_CPU_USB_DN
CLK_100M_CPU_SATA3_DP
CLK_100M_CPU_SATA3_DN
CLK_100M_CPU_MPLL1_DN
CLK_100M_CPU_MPLL1_DP
CLK_100M_CPU_GBE_DP
CLK_100M_CPU_GBE_DN
CLK_14M_CPU_R
CLKREQB
CLK_100M_SATA2_DP
CLK_100M_SATA2_DN
CLK_GEN_R_PG
P3V3_CLK_XTAL
XTAL_CLK_GEN_IN
XTAL_CLK_GEN_OUT_R XTAL_CLK_GEN_OUT
P3V3_STBY
P1V5_STBY
P3V3_STBY
P3V3_STBY
P3V3_STBY
P3V3_STBY
P3V3_CLK_XTAL
P3V3_CLK_VDD25
P3V3_CLK_PCI
P1V5_CLK_VDD_CORE
P1V5_CLK_VDDDIF
P1V5_CLK_SCR_LVIO
CLK_14M_CPU15
CLK_100M_XDP_R_DP 24
CLK_100M_XDP_R_DN 24
CLK_100M_CPU_HFHPLL_DP 15
CLK_100M_CPU_HFHPLL_DN 15
CLK_100M_CPU_MPLL0_DP 11
CLK_100M_CPU_MPLL0_DN 11
CLK_100M_CLKBUFF_DP 32
CLK_100M_CLKBUFF_DN 32
CLK_96M_CPU_USB_DP 14
CLK_96M_CPU_USB_DN 14
CLK_100M_CPU_SATA3_DP 14
CLK_100M_CPU_SATA3_DN 14
CLK_100M_CPU_MPLL1_DP 12
CLK_100M_CPU_MPLL1_DN 12
CLK_100M_CPU_GBE_DP17
CLK_100M_CPU_GBE_DN17
CLK_100M_SATA2_DN14
CLK_100M_SATA2_DP14
CLK_GEN_PG22,32,46,53
SMB_HOST_LV_CLK22,26,27,28,29,30,35
SMB_HOST_LV_DATA22,26,27,28,29,30,35
Title 
Size Document Number R e v 
Date: Sheet 
o f 
Honey_Badger_uServer 1B
CLOCK GEN 4420
A3
31 56Tuesday, January 20, 2015
Wiwynn Incorporated
http://www.wiwynn.com
8F, 90, Sec.1, Xintai 5th Rd., Xizhi Dist.,
New Taipei City 22102, Taiwan (R.O.C.)
Title 
Size Document Number R e v 
Date: Sheet 
o f 
Honey_Badger_uServer 1B
CLOCK GEN 4420
A3
31 56Tuesday, January 20, 2015
Wiwynn Incorporated
http://www.wiwynn.com
8F, 90, Sec.1, Xintai 5th Rd., Xizhi Dist.,
New Taipei City 22102, Taiwan (R.O.C.)
Title 
Size Document Number R e v 
Date: Sheet 
o f 
Honey_Badger_uServer 1B
CLOCK GEN 4420
A3
31 56Tuesday, January 20, 2015
Wiwynn Incorporated
http://www.wiwynn.com
8F, 90, Sec.1, Xintai 5th Rd., Xizhi Dist.,
New Taipei City 22102, Taiwan (R.O.C.)
X2
XTAL-14D31818MHZ-1-GP
1 2
C52
SCD1U10V2KX-5GP
1 2
R1280R2J-2-GP 1 2
R138
10KR2F-2-GP
1 2
L12
BLM18PG330SN1D-GP
1 2
R127
33R2F-3-GP
12
C41
SCD1U10V2KX-5GP
1 2
R954K7R2F-GP 1 2
R126
0R2J-2-GP
NOPOP
1 2
C68
SC10U6D3V3MX-GP
1 2
R1290R2J-2-GP 1 2
R113
2D2R3J-2-GP1 2
U16
9VRS4420DKLFT-GP
X2 1X1 2
VREF0_2X/FSLA4
SDATA_3_35
SCLK_3_36
PCI_F1_2X8
PCI2_2X9
CLKREQA#/PCI3_2X10
VSEL_PCI/25M_PCI4_2X13
USB_48MHZ_2X 16
CLKREQB#18
PCI_STOP#_3_331
CLKPWRGD/PD#_3_347
GND49
GNDPCI 11
GND25 12
GND48 17
GNDSATA 24
GNDSRC 25
GNDSRC 34
GNDDIF 44
GNDREF 48
DOT96_LRS/SRC6_LRS 19
DOT96#_LRS/SRC6#_LRS 20
SRC1#_LRS 38SRC1_LRS 39VDDPCI_3_37
VDDSRC_LVIO30
VDD_CORE_1_521
VDD_CORE_1_540
VDDDIF_CORE_1_541
VDD2514
VDD4815
VDDREF3
SRC2#_LRS 35SRC2_LRS 36
SRC3#_LRS 32SRC3_LRS 33
SRC4#_LRS 28SRC4_LRS 29
SRC5#_LRS 26SRC5_LRS 27
SATA_LRS 22
SATA#_LRS 23DIF0_LRS46
DIF0#_LRS45
DIF1_LRS43
DIF1#_LRS42
DIF_STOP#_3_337
R83
1KR2F-3-GP
1 2
L13
BLM18PG330SN1D-GP
1 2
R125 0R2J-2-GP1 2
R102
1KR2F-3-GP
1 2
C66
SC27P50V2GN-GP
1 2
C24
SC10U6D3V3MX-GP
1 2
R132
2D2R3J-2-GP1 2
C53
SC10U6D3V3MX-GP
1 2
C43
SC10U6D3V3MX-GP
1 2
R137
10KR2F-2-GP
NOPOP
1 2
L1
BLM18PG330SN1D-GP
1 2
C51
SCD1U10V2KX-5GP
1 2
C65
SC27P50V2GN-GP
1 2
C25
SCD1U10V2KX-5GP
1 2
C67
SC10U6D3V3MX-GP
1 2
L14
BLM18PG330SN1D-GP
1 2
L3
BLM18PG330SN1D-GP
1 2
C35
SCD1U10V2KX-5GP
1 2
C61
SCD1U10V2KX-5GP
1 2
L2
BLM18PG330SN1D-GP
1 2
C62
SCD1U10V2KX-5GP
1 2
R120
0R2J-2-GP
1 2
C36
SC10U6D3V3MX-GP
1 2



5
5
4
4
3
3
2
2
1
1
D D
C C
B B
A A
SMBus Address: 0xD8 (11011000) 
 
P3V3_VDDA_CLKBUFF_R P3V3_VDDA_CLKBUFF
P3V3_VDD_CLKBUFF
SMB_CLKBUFF_R_DATA
SMB_CLKBUFF_R_CLK
CLK_GEN_PG
CLK_100M_CLKBUFF_DN
CLK_100M_CLKBUFF_DP
P3V3_VDD_CLKBUFF
CLKBUFF_IREF
CLKBUFF_SRC_DIV#
CLKBUFF_BYPASS_OR_PLL
CLKCUFF_SMB_ADDRCLKBUFF_BYPASS_OR_PLL
CLKBUFF_OE0#
CLKBUFF_OE7#
CLKBUFF_OE1#
CLKBUFF_OE0#
CLKBUFF_OE3#
CLKBUFF_OE2#
CLKBUFF_OE5#
CLKBUFF_OE4#
CLKBUFF_OE6#
CLKCUFF_SMB_ADDR
P3V3_VDDA_CLKBUFF
CLK_GEN_PG
CLKBUFF_OE1#
CLKBUFF_OE2#
CLKBUFF_OE5#
CLKBUFF_OE3#
CLKBUFF_OE4#
CLKBUFF_OE7#
CLKBUFF_OE6#
CLK_100M_CLKBUFF_SAS_R_DP
CLK_100M_CLKBUFF_SAS_R_DN
CLK_100M_CLKBUFF_ENET_R_DP
CLK_100M_CLKBUFF_ENET_R_DN
CLK_100M_PCIE2_REFCLK_R_DN
CLK_100M_PCIE2_REFCLK_R_DP
CLK_100M_CLKBUFF_PCIE_R_DP
CLK_100M_CLKBUFF_PCIE_R_DN
CLK_100M_CLKBUFF_NGFF_R_DN
CLK_100M_CLKBUFF_NGFF_R_DP
P3V3_VDD_CLKBUFF_R
P3V3
P3V3
P3V3
P3V3
P3V3
P3V3
P3V3_VDDA_CLKBUFF
P3V3_VDD_CLKBUFF
CLK_GEN_PG22,31,46,53
CLK_100M_CLKBUFF_DP31
CLK_100M_CLKBUFF_DN31
CLK_100M_PCIE_SAS_DN 37
CLK_100M_CLKBUFF_ENET_DN 37
CLK_100M_CLKBUFF_ENET_DP 37
CLK_100M_PCIE_SAS_DP 37
CLK_100M_PCIE2_REFCLK_DP 37
CLK_100M_PCIE2_REFCLK_DN 37
CLK_100M_CLKBUFF_PCIE_DP 13
CLK_100M_CLKBUFF_PCIE_DN 13
CLK_100M_CLKBUFF_NGFF_DP 34
CLK_100M_CLKBUFF_NGFF_DN 34
SMBUS_HOST_CLK15,16,22,24
SMBUS_HOST_DATA15,16,22,24
Title 
Size Document Number R ev 
Date: Sheet 
o f 
Honey_Badger_uServer 1B
CLOCK BUFFER
Custom
32 56Tuesday, January 20, 2015
Wiwynn Incorporated
http://www.wiwynn.com
8F, 90, Sec.1, Xintai 5th Rd., Xizhi Dist.,
New Taipei City 22102, Taiwan (R.O.C.)
Title 
Size Document Number R ev 
Date: Sheet 
o f 
Honey_Badger_uServer 1B
CLOCK BUFFER
Custom
32 56Tuesday, January 20, 2015
Wiwynn Incorporated
http://www.wiwynn.com
8F, 90, Sec.1, Xintai 5th Rd., Xizhi Dist.,
New Taipei City 22102, Taiwan (R.O.C.)
Title 
Size Document Number R ev 
Date: Sheet 
o f 
Honey_Badger_uServer 1B
CLOCK BUFFER
Custom
32 56Tuesday, January 20, 2015
Wiwynn Incorporated
http://www.wiwynn.com
8F, 90, Sec.1, Xintai 5th Rd., Xizhi Dist.,
New Taipei City 22102, Taiwan (R.O.C.)
R369 33R2F-3-GP1 2
R432
43D2R2F-GP 1 2
R325
4K7R2F-GP
NOPOP
1 2
R449
4K7R2F-GP
1 2
R448
4K7R2F-GP
NOPOP
1 2
R446
4K7R2F-GP
NOPOP
1 2
L10
BLM18PG330SN1D-GP
1 2
R359
4K7R2F-GP
NOPOP
1 2
R4350R2J-2-GP 1 2
C309
SCD1U10V2KX-5GP
1 2
R363
4K7R2F-GP
1 2
R4360R2J-2-GP 1 2
R361
2D2R3J-2-GP1 2
R440
4K7R2F-GP
NOPOP
1 2
R447
4K7R2F-GP
NOPOP
1 2C209
SCD1U10V2KX-5GP
1 2
R439
10KR2F-2-GP
1 2
R328 33R2F-3-GP1 2
R418
43D2R2F-GP 1 2
L11
BLM18PG330SN1D-GP
1 2
C208
SCD1U10V2KX-5GP
1 2
R351 33R2F-3-GP1 2
R343
4K7R2F-GP
1 2
R60
2D2R3J-2-GP1 2
R424
43D2R2F-GP 1 2
R346
4K7R2F-GP
NOPOP
1 2
R425
43D2R2F-GP 1 2
R341
4K7R2F-GP
1 2
C310
SCD1U10V2KX-5GP
1 2
R368 33R2F-3-GP1 2
R348
4K7R2F-GP
NOPOP
1 2
R420 33R2F-3-GP1 2
R354 33R2F-3-GP1 2
R453
4K7R2F-GP
NOPOP
1 2
R429
43D2R2F-GP 1 2
R450
4K7R2F-GP
NOPOP
1 2
C227
SC1U25V3KX-GP
1 2
R327 33R2F-3-GP1 2
C201
SCD1U10V2KX-5GP
1 2
R427
43D2R2F-GP 1 2
R326
4K7R2F-GP
1 2
R441
4K7R2F-GP
1 2
R355 33R2F-3-GP1 2
C207
SCD1U10V2KX-5GP
1 2
R438
4K7R2F-GP
1 2
R431
43D2R2F-GP 1 2
R430
43D2R2F-GP 1 2
R349 33R2F-3-GP1 2
R454
432R2F-GP
12
R455
4K7R2F-GP
1 2
R451
4K7R2F-GP
1 2
U28
9DB833AGILFT-GP
VDDR2
GND 3
SRC_IN4
GND 10
VDD11
GND 18
VDD19
SMBCLK23
SMBDAT24
VDDA48
GNDA 47IREF46 LOCK45
VDD39
GND 32
VDD31
SMB_ADR_TRI28
VDD27
GND 26GND 25
SRC_DIV#1 SRC_IN#5
OE0#6
OE3#7
DIF_0# 9
DIF_1# 13
OE1#14
OE2#15
DIF_2# 17
DIF_3# 21
BYP#_HIBW_LOBW22
OE7#44
OE4#43
DIF_7# 41
PD#40
DIF_6# 37
OE6#36 OE5#35
DIF_5# 33
DIF_4# 29
DIF_7 42
DIF_6 38
DIF_5 34
DIF_4 30
DIF_0 8
DIF_1 12
DIF_2 16
DIF_3 20
R437
4K7R2F-GP
1 2
R452
4K7R2F-GP
1 2
C39
SC10U25V5KX-GP
1 2
R419 33R2F-3-GP1 2
C206
SCD1U10V2KX-5GP
1 2
R428
43D2R2F-GP 1 2
R426
43D2R2F-GP 1 2



5
5
4
4
3
3
2
2
1
1
D D
C C
B B
A A
SATA3_RX_C_DP0
SATA3_RX_C_DN0
MSATA_PRESENT_R#
MSATA_PRESENT_R#
MSATA_ACT#
LED_MSATA_DAS_R MSATA_ACT#
SATA3_TX_C_DN0
SATA3_TX_C_DP0
P3V3
P3V3_CPU
P3V3
P3V3
SATA3_RX_DN0 14
SATA3_RX_DP0 14
SATA3_TX_DP0 14
SATA3_TX_DN0 14
MSATA_PRESENT#17
Title 
Size Document Number Rev 
Date: Sheet o f 
Honey_Badger_uServer 1B
M-SATA CONNECT
A4
33 56Tuesday, January 20, 2015
Wiwynn Incorporated
http://www.wiwynn.com
8F, 90, Sec.1, Xintai 5th Rd., Xizhi Dist.,
New Taipei City 22102, Taiwan (R.O.C.)
Title 
Size Document Number Rev 
Date: Sheet o f 
Honey_Badger_uServer 1B
M-SATA CONNECT
A4
33 56Tuesday, January 20, 2015
Wiwynn Incorporated
http://www.wiwynn.com
8F, 90, Sec.1, Xintai 5th Rd., Xizhi Dist.,
New Taipei City 22102, Taiwan (R.O.C.)
Title 
Size Document Number Rev 
Date: Sheet o f 
Honey_Badger_uServer 1B
M-SATA CONNECT
A4
33 56Tuesday, January 20, 2015
Wiwynn Incorporated
http://www.wiwynn.com
8F, 90, Sec.1, Xintai 5th Rd., Xizhi Dist.,
New Taipei City 22102, Taiwan (R.O.C.)
R158
4K7R2F-GP
NOPOP
1 2
C45 SCD01U16V2KX-3GP12
R504
4K7R2F-GP
NOPOP
1 2
C302
SC1U6D3V2KX-GP
1 2
CN5
SKT-MINI52P-67-GP-U
3.3V2
1.5V6
+3.3VAUX24
+1.5V28
+1.5V48
+3.3V52
GND 4
GND 9
GND 15
GND 18
GND 21
GND 26
GND 27
GND 29
GND 34
GND 35
GND 40
GND 50
GND 53
GND 54
RESERVED#33
RESERVED#55
RESERVED#88
RESERVED#1010
RESERVED#1212
RESERVED#1414
RESERVED#1616
RESERVED#1717
RESERVED#1919
RESERVED#2020
RESERVED#3737
RESERVED#3939
RESERVED#4141
RESERVED#4343
RESERVED#4545
RESERVED#4747
RESERVED#4949
RESERVED#5151
REFCLK+ 13
REFCLK- 11
PERP0 23
PERN0 25
PETN0 31
PETP0 33
USB_D- 36
USB_D+ 38
WAKE# 1
CLKREQ# 7
PERST# 22
SMB_CLK 30
SMB_DATA 32
LED_WWAN#42
LED_WLAN#44
LED_WPAN#46
NP1 NP1 
NP2 NP2 
R411 0R2J-2-GP1 2
C282 SCD01U16V2KX-3GP12
C283 SCD01U16V2KX-3GP12
C231
SCD1U16V2KX-3GP
1 2
R157
4K7R2F-GP
1 2
C303
SCD1U16V2KX-3GP
1 2
C48 SCD01U16V2KX-3GP12
R394
300R2F-GP
1 2
C304
SCD1U16V2KX-3GP
1 2
LED16
LED-YG-51-GP
A K



5
5
4
4
3
3
2
2
1
1
D D
C C
B B
A A
RST_PCIE_PCH_DEV_R#
PEDET_SEL
LED_NGFF_DASLED_NGFF_DAS_R
P2E_CPU_NGFF_C_RX_DP12
P2E_CPU_NGFF_C_RX_DN12
P2E_CPU_NGFF_TX_DP12
P2E_CPU_NGFF_TX_DN12
NGFF_PRESENT_R#
NGFF_PRESENT_R#
P2E_CPU_NGFF_TX_DN13
P2E_CPU_NGFF_TX_DP13
P2E_CPU_NGFF_TX_DN14
P2E_CPU_NGFF_TX_DP14
P2E_CPU_NGFF_TX_DN15
P2E_CPU_NGFF_TX_DP15
P2E_CPU_NGFF_C_RX_DP13
P2E_CPU_NGFF_C_RX_DN13
P2E_CPU_NGFF_C_RX_DP14
P2E_CPU_NGFF_C_RX_DN14
P2E_CPU_NGFF_C_RX_DP15
P2E_CPU_NGFF_C_RX_DN15
P3V3
P3V3
P3V3
P3V3_CPU
P3V3
P2E_CPU_NGFF_RX_DN12 13
P2E_CPU_NGFF_RX_DP12 13
PMU_SUS_CLK15,16
CLK_100M_CLKBUFF_NGFF_DP 32
CLK_100M_CLKBUFF_NGFF_DN 32
P2E_CPU_NGFF_C_TX_DP12 13
P2E_CPU_NGFF_C_TX_DN12 13
SATA3_RX_DP1 14
SATA3_RX_DN1 14
SATA3_TX_DN1 14
SATA3_TX_DP1 14
PMU_PLTRST#15,37,38,53
NGFF_PRESENT# 17
P2E_CPU_NGFF_RX_DN13 13
P2E_CPU_NGFF_RX_DP13 13
P2E_CPU_NGFF_C_TX_DN13 13
P2E_CPU_NGFF_C_TX_DP13 13
P2E_CPU_NGFF_RX_DN14 13
P2E_CPU_NGFF_C_TX_DN14 13
P2E_CPU_NGFF_RX_DP14 13
P2E_CPU_NGFF_C_TX_DP14 13
P2E_CPU_NGFF_RX_DN15 13
P2E_CPU_NGFF_RX_DP15 13
P2E_CPU_NGFF_C_TX_DN15 13
P2E_CPU_NGFF_C_TX_DP15 13
Title 
Size Document Number R e v 
Date: Sheet 
o f 
Honey_Badger_uServer 1B
NGFF
A3
34 56Tuesday, January 20, 2015
Wiwynn Incorporated
http://www.wiwynn.com
8F, 90, Sec.1, Xintai 5th Rd., Xizhi Dist.,
New Taipei City 22102, Taiwan (R.O.C.)
Title 
Size Document Number R e v 
Date: Sheet 
o f 
Honey_Badger_uServer 1B
NGFF
A3
34 56Tuesday, January 20, 2015
Wiwynn Incorporated
http://www.wiwynn.com
8F, 90, Sec.1, Xintai 5th Rd., Xizhi Dist.,
New Taipei City 22102, Taiwan (R.O.C.)
Title 
Size Document Number R e v 
Date: Sheet 
o f 
Honey_Badger_uServer 1B
NGFF
A3
34 56Tuesday, January 20, 2015
Wiwynn Incorporated
http://www.wiwynn.com
8F, 90, Sec.1, Xintai 5th Rd., Xizhi Dist.,
New Taipei City 22102, Taiwan (R.O.C.)
C34 SCD1U16V2KX-3GPNOPOP 1 2
C59 SCD1U16V2KX-3GPNOPOP 1 2
C37 SCD1U16V2KX-3GPNOPOP 1 2
C159
SC10U6D3V5KX-4GP
1 2
C30
SC1U6D3V2KX-GP
1 2
C42 SCD1U16V2KX-3GPNOPOP 1 2
C248
SCD1U16V2KX-3GP
1 2
C184 SCD1U16V2KX-3GPNOPOP 1 2
C170
SCD1U16V2KX-3GP
1 2
C250
SC1U6D3V2KX-GP
1 2
C64 SCD01U16V2KX-3GP12
C60 SCD01U16V2KX-3GP12
C247
SC1U6D3V2KX-GP
1 2
R315
4K7R2F-GP
NOPOP
1 2
R408
4K7R2F-GP
1 2
R144
10KR2F-2-GP
1 2
C177
SCD1U16V2KX-3GP
1 2
R305
300R2F-GP
1 2
C57 SCD1U16V2KX-3GPNOPOP 1 2
C63 SCD1U16V2KX-3GPNOPOP 1 2
C50 SCD1U16V2KX-3GPNOPOP 1 2
C55 SCD1U16V2KX-3GPNOPOP 1 2
C249
SCD1U16V2KX-3GP
1 2
C40 SCD1U16V2KX-3GPNOPOP 1 2
C196 SCD1U16V2KX-3GPNOPOP 1 2
C58 SCD01U16V2KX-3GP12
R505
4K7R2F-GP
NOPOP
12
C173
SCD1U16V2KX-3GP
1 2
C56 SCD01U16V2KX-3GP12
C158
SC10U6D3V5KX-4GP
1 2
R370
0R2J-2-GP
1 2
C181 SCD1U16V2KX-3GPNOPOP 1 2
LED15
LED-YG-51-GP
A K
C189 SCD1U16V2KX-3GPNOPOP 1 2
C47 SCD1U16V2KX-3GPNOPOP 1 2
NGFF1
SKT-MINI67P-10-GP
7676 77 77NP1 NP1NP2NP2
3_3V2 3_3V4 NC#66 NC#88 DAS/DSS#10 3_3V12 3_3V14 3_3V16 3_3V18 NC#2020 NC#2222 NC#2424 NC#2626 NC#2828 NC#3030 NC#3232 NC#3434 NC#3636 DEVSLP38 NC#4040 NC#4242 NC#4444 NC#4646 NC#4848 PERST#/NC#5050 CLKREQ#/NC#5252 PEWAKE#/NC#5454 NC#5656 NC#5858
SUSCLK(32KHZ)68 3_3V70 3_3V72 3_3V74
GND 1GND 3PERN3 5PERP3 7GND 9PETN3 11PETP3 13GND 15PERN2 17PERP2 19GND 21PETN2 23PETP2 25GND 27PERN1 29PERP1 31GND 33PETN1 35PETP1 37GND 39PERN0/SATA-B+ 41PERP0/SATA-B- 43GND 45PETN0/SATA-A- 47PETP0/SATA-A+ 49GND 51REFCLKN 53REFCLKP 55GND 57
NC#67 67PEDET(NC-PCIE/GND-SATA) 69GND 71GND 73GND 75
C44 SCD1U16V2KX-3GPNOPOP 1 2
C32 SCD1U16V2KX-3GPNOPOP 1 2
R407
0R2J-2-GP
1 2
C31
SC1U6D3V2KX-GP
1 2



5
5
4
4
3
3
2
2
1
1
D D
C C
B B
A A
ADD=1001001 (0x92) 
VOLTAGE SENSOR 
ADD=1001100 (0x98) 
TEMP SENSOR ADD=1010001 (0xA2) 
EEPROM 
PVCCP_SENSE
PVNN_SENSE
PV_VDDR_SENSE
P1V0_SENSE
TEMP_1_A0
TEMP_1_CLK
TEMP_1_ALERT#
TEMP_1_DATA
TEMP_1_A1
TEMP_1_A2
BMC_I2C_DATA
EEPROM_A0
BMC_I2C_CLK
EEPROM_A1 EEPROM_WP
EEPROM_DATA
EEPROM_A2
EEPROM_CLK
P3V3_STBY_SENSE
P12V_SENSE
P1V8_SENSE
P3V3_SENSE
BMC_I2C_CLK
BMC_I2C_DATA
BMC_I2C_CLK
BMC_I2C_DATA
PCIE_GF_I2C_CLK
PCIE_GF_I2C_DATA
PCIE_GF_I2C_ALERT#
BMC_I2C_ALERT#
PICE_GF_I2C_SW_EN
BMC_I2C_CLK
BMC_I2C_DATA
BMC_I2C_ALERT# PCIE_GF_I2C_ALERT#
PCIE_GF_I2C_DATA
PCIE_GF_I2C_CLK
BMC_I2C_ALERT#
PCIE_GF_I2C_CLK
PCIE_GF_I2C_ALERT#
PCIE_GF_I2C_DATA
VOL1_SEN_ADDR0
VOL1_SEN_ADDR1
VOL1_SEN_ADDR0 VOL1_SEN_ADDR1
VOL1_SEN_CLK
VOL1_SEN_DATA
VOL1_SEN_VREF
P3V3_STBY
PVCCP PVNN P1V0 PV_VDDR
P3V3_STBY P3V3_STBY
P3V3_STBY
P3V3_STBY
P3V3_STBY
P3V3_STBY
P1V8P3V3P3V3_STBYP12V
P3V3_STBYP3V3_STBY
P3V3_STBY
PCIE_GF_I2C_ALERT# 37
PCIE_GF_I2C_CLK 37
CPU_RSMRST#15,16,24,37,39,46
PCIE_GF_I2C_DATA37 BMC_I2C_DATA 38,39
BMC_I2C_CLK38,39
BMC_I2C_ALERT# 38
TEMP_1_ALERT#38
BMC_I2C_DATA 38,39
BMC_I2C_CLK 38,39
SMB_HOST_LV_DATA 22,26,27,28,29,30,31
SMB_HOST_LV_CLK 22,26,27,28,29,30,31
SMB_HOST_LV_DATA22,26,27,28,29,30,31
SMB_HOST_LV_CLK22,26,27,28,29,30,31
Title 
Size Document Number R ev 
Date: Sheet 
of 
Honey_Badger_uServer 1B
I2C SENSOR DEVICE
Custom
35 56Tuesday, January 20, 2015
Wiwynn Incorporated
http://www.wiwynn.com
8F, 90, Sec.1, Xintai 5th Rd., Xizhi Dist.,
New Taipei City 22102, Taiwan (R.O.C.)
Title 
Size Document Number R ev 
Date: Sheet 
of 
Honey_Badger_uServer 1B
I2C SENSOR DEVICE
Custom
35 56Tuesday, January 20, 2015
Wiwynn Incorporated
http://www.wiwynn.com
8F, 90, Sec.1, Xintai 5th Rd., Xizhi Dist.,
New Taipei City 22102, Taiwan (R.O.C.)
Title 
Size Document Number R ev 
Date: Sheet 
of 
Honey_Badger_uServer 1B
I2C SENSOR DEVICE
Custom
35 56Tuesday, January 20, 2015
Wiwynn Incorporated
http://www.wiwynn.com
8F, 90, Sec.1, Xintai 5th Rd., Xizhi Dist.,
New Taipei City 22102, Taiwan (R.O.C.)
R422 0R2J-2-GP
NOPOP
1 2
R179
0R2J-2-GP
1 2
U29
2N7002DW-7F-GP
1
2
3 4
5
6
R173
4K7R2F-GP
1 2 U22
M24128-BWMN6TP-GP
E01
E12
E23
VSS4 SDA 5SCL 6WC# 7VCC 8
R178
4K7R2F-GP
1 2
R417
0R2J-2-GP
1 2
R166
0R2J-2-GP
1 2
R301
4K7R2F-GP
1 2
R503
10KR2F-2-GP 
1 2
C70
SCD1U16V2KX-3GP
1 2
Q15
2N7002A-7-GP
G
SD
C85
SCD1U16V2KX-3GP
1 2 R421 0R2J-2-GP
NOPOP
1 2
R4
0R2J-2-GP
1 2
R183
4K7R2F-GP
NOPOP
1 2
C79
SCD1U16V2KX-3GP 
1 2
R461
4K7R2F-GP
1 2
R159
10KR2F-2-GP 
1 2
C83
SCD1U16V2KX-3GP
1 2
R495
2K2R2F-GP 
1 2
R134
0R2J-2-GP
1 2
R423 0R2J-2-GP
NOPOP
1 2
C69
SCD1U16V2KX-3GP
1 2
R171
4K7R2F-GP
NOPOP
1 2
R7
4K7R2F-GP
1 2
R312
4K7R2F-GP
1 2R172
10KR2F-2-GP
1 2
R191
0R2J-2-GP
1 2
C84
SCD1U16V2KX-3GP
1 2
R3
4K7R2F-GP
1 2
R11
4K7R2F-GP
NOPOP
1 2
C77
SCD1U16V2KX-3GP 
1 2
R189
0R2J-2-GP
1 2
R133
0R2J-2-GP
1 2
R146
10KR2F-2-GP 
1 2
R181
4K7R2F-GP
1 2
U1
TMP75AIDGKR-GP
SDA1
SCL2
ALERT3
GND4 A2 5A1 6A0 7V+ 8
R486
10KR2F-2-GP 
1 2
C71
SCD1U16V2KX-3GP
1 2
R6
4K7R2F-GP
1 2
R176
4K7R2F-GP
NOPOP
1 2
R463
4K7R2F-GP
NOPOP
1 2
R186
4K7R2F-GP
1 2
R464
4K7R2F-GP
NOPOP
1 2
R136 0R2J-2-GP1 2
R185
4K7R2F-GP
1 2
C78
SCD1U16V2KX-3GP
1 2
R187
4K7R2F-GP
NOPOP
1 2
C86
SCD1U16V2KX-3GP
1 2
R190
0R2J-2-GP
1 2
C4
SCD1U16V2KX-3GP
1 2
R12
4K7R2F-GP
1 2
R192
4K7R2F-GP
NOPOP
1 2
R5
4K7R2F-GP
NOPOP
1 2
R462
4K7R2F-GP
NOPOP
1 2
R8
0R2J-2-GP
1 2
R135 0R2J-2-GP1 2
R184
0R2J-2-GP
1 2
R9
4K7R2F-GP
NOPOP
1 2
U19
ADS7828E-2K5-GP
CH01
CH12
CH23
CH34
CH45
CH56
CH67
CH78 GND 9VREF 10COM 11A0 12A1 13SCL 14SDA 15VDD 16
C80SCD1U25V2KX-2-GP 
1 2



5
5
4
4
3
3
2
2
1
1
D D
C C
B B
A A
JTAG_CPU_PLD_TDO
JTAG_PLD_TDO
JTAG_PLD_TMS
JTAG_PLD_TCK
JTAG_RST#
JTAG_CHAIN_EN
JTAG_CHAIN_EN
XDP_SOC_CPU_TDO
XDP_SOC_CPU_TDI
JTAG_PLD_TCK_D
JTAG_PLD_TMS_D
JTAG_PLD_TDO_D
JTAG_RST_D#
XDP_SOC_CPU_TDI_S
XDP_SOC_CPU_TCK_S XDP_SOC_CPU_TCK
XDP_SOC_CPU_TMS XDP_SOC_CPU_TMS_S
XDP_SOC_CPU_TRST# XDP_SOC_CPU_TRST#_S
JTAG_CPU_PLD_TDO_D
XDP_SOC_CPU_TDO_S
JTAG_CHAIN_EN
P3V3_CPU
JTAG_PLD_TCK39
JTAG_PLD_TMS 39
JTAG_RST# 39
JTAG_PLD_TDO39
JTAG_CPU_PLD_TDO 39
XDP_SOC_CPU_TDO 15,24
XDP_SOC_CPU_TDI 15,24
XDP_SOC_CPU_TCK 15,24
XDP_SOC_CPU_TMS15,24
XDP_SOC_CPU_TRST#15,24
Title 
Size Document Number R e v 
Date: Sheet 
o f 
Honey_Badger_uServer 1B
BLANK
A3
36 56Tuesday, January 20, 2015
Wiwynn Incorporated
http://www.wiwynn.com
8F, 90, Sec.1, Xintai 5th Rd., Xizhi Dist.,
New Taipei City 22102, Taiwan (R.O.C.)
Title 
Size Document Number R e v 
Date: Sheet 
o f 
Honey_Badger_uServer 1B
BLANK
A3
36 56Tuesday, January 20, 2015
Wiwynn Incorporated
http://www.wiwynn.com
8F, 90, Sec.1, Xintai 5th Rd., Xizhi Dist.,
New Taipei City 22102, Taiwan (R.O.C.)
Title 
Size Document Number R e v 
Date: Sheet 
o f 
Honey_Badger_uServer 1B
BLANK
A3
36 56Tuesday, January 20, 2015
Wiwynn Incorporated
http://www.wiwynn.com
8F, 90, Sec.1, Xintai 5th Rd., Xizhi Dist.,
New Taipei City 22102, Taiwan (R.O.C.)
U25
2N7002DW-7F-GP
1
2
3 4
5
6
R401
10KR2F-2-GP
NOPOP
1 2
R2070R2J-2-GP
NOPOP
1 2
R216 0R2J-2-GP
NOPOP
12
R214
10KR2F-2-GP
1 2
R199 0R2J-2-GP
NOPOP
12
R210 0R2J-2-GP
NOPOP
12
R211 0R2J-2-GP
NOPOP
12
R205 0R2J-2-GP
NOPOP
12
R2150R2J-2-GP
NOPOP
1 2
U24
2N7002DW-7F-GP
1
2
3 4
5
6
R2060R2J-2-GP
NOPOP
1 2
R2120R2J-2-GP
NOPOP
1 2
Q6
2N7002A-7-GP
G
SD
R213 0R2J-2-GP
NOPOP
12



5
5
4
4
3
3
2
2
1
1
D D
C C
B B
A A
BOARD_PRSNT#
USB_P1_DN
USB_P1_DP
GF_CPU_TXD
GF_CPU_RXD
PCIE_GF_I2C_CLK
PCIE_GF_I2C_DATA
CPU_GBE_RX_DN0
CPU_GBE_RX_DP0
CPU_GBE_TX_C_DP0
CPU_GBE_TX_C_DN0
SATA2_TX_C_DN0
SATA2_TX_C_DP0
PCIE_RESET#
PMU_BUF_PLTRST#
SATA2_TX_DN0
SATA2_TX_DP0
PCIE_GF_I2C_R_ALERT#
SATA2_RX_C_DP0
SATA2_RX_C_DN0
CPU_GBE_TX_DN0
CPU_GBE_TX_DP0
CPU_GBE_RX_C_DP0
CPU_GBE_RX_C_DN0
PCIE_RSVD_A41
GBE_R_SMBALRT#
GBE_R_SMBCLK
GBE_R_SMDATA
CLK_100M_CLKBUFF_ENET_DP
CLK_100M_CLKBUFF_ENET_DN
P2E_CPU_ETH10G_RX_DP8
P2E_CPU_ETH10G_RX_DN8
P2E_CPU_SAS_RX_DP1
P2E_CPU_SAS_RX_DN1
P2E_CPU_SAS_RX_DP2
P2E_CPU_SAS_RX_DN2
P2E_CPU_SAS_RX_DN0
P2E_CPU_SAS_RX_DP0
P2E_CPU_SAS_RX_DP3
P2E_CPU_SAS_RX_DN3
CLK_100M_PCIE_SAS_DP
CLK_100M_PCIE_SAS_DN
P2E_CPU_SAS_RX_DN4
P2E_CPU_SAS_RX_DP4
P2E_CPU_SAS_RX_DP5
P2E_CPU_SAS_RX_DN5
P2E_CPU_SAS_RX_DP6
P2E_CPU_SAS_RX_DN6
P2E_CPU_SAS_RX_DP7
P2E_CPU_SAS_RX_DN7
P2E_CPU_SAS_C_TX_DN0
P2E_CPU_SAS_C_TX_DP0
P2E_CPU_SAS_TX_DN0
P2E_CPU_SAS_TX_DP0
P2E_CPU_ETH10G_C_TX_DP8
P2E_CPU_ETH10G_C_TX_DN8 P2E_CPU_ETH10G_TX_DN8
P2E_CPU_ETH10G_TX_DP8
P2E_CPU_SAS_TX_DP1
P2E_CPU_SAS_TX_DN1
P2E_CPU_SAS_TX_DP2
P2E_CPU_SAS_TX_DN2
P2E_CPU_SAS_TX_DP3
P2E_CPU_SAS_TX_DN3
P2E_CPU_SAS_C_TX_DP1
P2E_CPU_SAS_C_TX_DN1
P2E_CPU_SAS_C_TX_DN2
P2E_CPU_SAS_C_TX_DP2
P2E_CPU_SAS_C_TX_DN3
P2E_CPU_SAS_C_TX_DP3
P2E_CPU_SAS_TX_DP4
P2E_CPU_SAS_TX_DN4
P2E_CPU_SAS_TX_DP5
P2E_CPU_SAS_TX_DN5
P2E_CPU_SAS_TX_DN6
P2E_CPU_SAS_TX_DP6
P2E_CPU_SAS_TX_DN7
P2E_CPU_SAS_TX_DP7
P2E_CPU_SAS_C_TX_DN4
P2E_CPU_SAS_C_TX_DP4
P2E_CPU_SAS_C_TX_DN5
P2E_CPU_SAS_C_TX_DP5
P2E_CPU_SAS_C_TX_DN6
P2E_CPU_SAS_C_TX_DP6
P2E_CPU_SAS_C_TX_DN7
P2E_CPU_SAS_C_TX_DP7
P2E_CPU_ETH10G_C_TX_DN9
P2E_CPU_ETH10G_C_TX_DP9
P2E_CPU_ETH10G_C_TX_DN10
P2E_CPU_ETH10G_C_TX_DP10
P2E_CPU_ETH10G_C_TX_DN11
P2E_CPU_ETH10G_C_TX_DP11
P2E_CPU_ETH10G_TX_DN9
P2E_CPU_ETH10G_TX_DP9
P2E_CPU_ETH10G_TX_DN10
P2E_CPU_ETH10G_TX_DP10
P2E_CPU_ETH10G_TX_DN11
P2E_CPU_ETH10G_TX_DP11
P2E_CPU_ETH10G_RX_DN9
P2E_CPU_ETH10G_RX_DP9
P2E_CPU_ETH10G_RX_DP10
P2E_CPU_ETH10G_RX_DN11
P2E_CPU_ETH10G_RX_DP11
CLK_100M_PCIE2_REFCLK_DP
CLK_100M_PCIE2_REFCLK_DN
PMU_BUF_PLTRST#
PMU_BUF_PLTRST#
PMU_BUF_PLTRST#
PMU_BUF_PLTRST#
CPU_TXD
CPU_RXD
GF_CPU_TXD
GF_CPU_RXD
GF_CPU_RXD CPU_RXD
PWR_BTN#
SLOT_ID2
SLOT_ID3
SLOT_ID1
SLOT_ID0
SLOT_ID3
SLOT_ID2
SLOT_ID1
SLOT_ID0
BMC_SYS_RESET#
GF_CPU_TXDCPU_TXD
PCIE1_RESET#
PCIE2_RESET#
GF_GBE_SMBALRT#
GBE_SMBALRT#
GF_GBE_SMB_SW_EN
GBE_SMBCLK GF_GBE_SMBCLK
GBE_SMBDATAGF_GBE_SMBDATA
GF_GBE_SMBALRT#
GF_GBE_SMBDATA
GF_GBE_SMBCLK
P2E_CPU_ETH10G_RX_DN10
P12V
P12V
P12V
P12V
P3V3
P3V3_STBY
P3V3_STBY
USB_P1_DP14
USB_P1_DN14
PCIE_GF_I2C_DATA35
CPU_GBE_TX_DN017
CPU_GBE_TX_DP017
CPU_GBE_RX_DN0 17
CPU_GBE_RX_DP0 17
SATA2_TX_DN014
SATA2_TX_DP014
SATA2_RX_DP0 14
SATA2_RX_DN0 14
PCIE_GF_I2C_CLK35
PCIE_GF_I2C_ALERT#35
P2E_CPU_ETH10G_RX_DP8 13
P2E_CPU_ETH10G_RX_DN8 13
CLK_100M_CLKBUFF_ENET_DN32
CLK_100M_CLKBUFF_ENET_DP32
P2E_CPU_SAS_RX_DP1 13
P2E_CPU_SAS_RX_DN1 13
P2E_CPU_SAS_RX_DN2 13
P2E_CPU_SAS_RX_DP2 13
P2E_CPU_SAS_RX_DN0 13
P2E_CPU_SAS_RX_DP0 13
P2E_CPU_SAS_RX_DP3 13
P2E_CPU_SAS_RX_DN3 13
CLK_100M_PCIE_SAS_DN 32
CLK_100M_PCIE_SAS_DP 32
P2E_CPU_SAS_RX_DN4 13
P2E_CPU_SAS_RX_DP4 13
P2E_CPU_SAS_RX_DP5 13
P2E_CPU_SAS_RX_DN5 13
P2E_CPU_SAS_RX_DN6 13
P2E_CPU_SAS_RX_DP6 13
P2E_CPU_SAS_RX_DN7 13
P2E_CPU_SAS_RX_DP7 13
P2E_CPU_SAS_C_TX_DN013
P2E_CPU_SAS_C_TX_DP013
P2E_CPU_ETH10G_C_TX_DP813
P2E_CPU_ETH10G_C_TX_DN813
P2E_CPU_SAS_C_TX_DP113
P2E_CPU_SAS_C_TX_DN113
P2E_CPU_SAS_C_TX_DN213
P2E_CPU_SAS_C_TX_DP213
P2E_CPU_SAS_C_TX_DN313
P2E_CPU_SAS_C_TX_DP313
P2E_CPU_SAS_C_TX_DP413
P2E_CPU_SAS_C_TX_DN413
P2E_CPU_SAS_C_TX_DN513
P2E_CPU_SAS_C_TX_DP513
P2E_CPU_SAS_C_TX_DP613
P2E_CPU_SAS_C_TX_DN613
P2E_CPU_SAS_C_TX_DN713
P2E_CPU_SAS_C_TX_DP713
P2E_CPU_ETH10G_C_TX_DP913
P2E_CPU_ETH10G_C_TX_DN913
P2E_CPU_ETH10G_C_TX_DP1013
P2E_CPU_ETH10G_C_TX_DN1013
P2E_CPU_ETH10G_C_TX_DN1113
P2E_CPU_ETH10G_C_TX_DP1113
P2E_CPU_ETH10G_RX_DP9 13
P2E_CPU_ETH10G_RX_DN9 13
P2E_CPU_ETH10G_RX_DP10 13
P2E_CPU_ETH10G_RX_DN10 13
P2E_CPU_ETH10G_RX_DN11 13
P2E_CPU_ETH10G_RX_DP11 13
CLK_100M_PCIE2_REFCLK_DN 32
CLK_100M_PCIE2_REFCLK_DP 32
PMU_PLTRST#15,34,38,53
CPU_RXD 15
BMC_PWRBTN#53
BMC_SYS_RESET#53
SLOT_ID2 38
SLOT_ID3 39
SLOT_ID1 38
SLOT_ID0 38
CPU_TXD15
CPU_RSMRST#15,16,24,35,39,46
GBE_SMBALRT# 17
GBE_SMBCLK17
GBE_SMBDATA 17
Title 
Size Document Number Rev 
Date: Sheet o f 
Honey_Badger_uServer 1B
PCIe GOLD FINGER
Custom
37 56Tuesday, January 20, 2015
Wiwynn Incorporated
http://www.wiwynn.com
8F, 90, Sec.1, Xintai 5th Rd., Xizhi Dist.,
New Taipei City 22102, Taiwan (R.O.C.)
Title 
Size Document Number Rev 
Date: Sheet o f 
Honey_Badger_uServer 1B
PCIe GOLD FINGER
Custom
37 56Tuesday, January 20, 2015
Wiwynn Incorporated
http://www.wiwynn.com
8F, 90, Sec.1, Xintai 5th Rd., Xizhi Dist.,
New Taipei City 22102, Taiwan (R.O.C.)
Title 
Size Document Number Rev 
Date: Sheet o f 
Honey_Badger_uServer 1B
PCIe GOLD FINGER
Custom
37 56Tuesday, January 20, 2015
Wiwynn Incorporated
http://www.wiwynn.com
8F, 90, Sec.1, Xintai 5th Rd., Xizhi Dist.,
New Taipei City 22102, Taiwan (R.O.C.)
C279 SCD1U16V2KX-3GP1 2
R3930R2J-2-GP 12
R3980R2J-2-GP 12
R442 0R2J-2-GP12
C286 SCD1U16V2KX-3GP1 2
C313 SCD047U25V2KX-GP1 2
Q18
2N7002A-7-GP
G
SD
C277 SCD1U16V2KX-3GP1 2
C270 SCD1U16V2KX-3GP1 2
C285 SCD1U16V2KX-3GP1 2
R444
4K7R2F-GP
1 2
R459
4K7R2F-GP
1 2
C267 SCD1U16V2KX-3GP1 2
C266 SCD1U16V2KX-3GP1 2
C275 SCD1U16V2KX-3GP1 2
C317
SCD1U10V2KX-5GP
1 2
R458
4K7R2F-GP
1 2
C264 SCD1U16V2KX-3GP1 2
C271 SCD1U16V2KX-3GP1 2
R1930R2J-2-GP 12
C315 SCD047U25V2KX-GP1 2
C306 SCD01U16V2KX-3GP12
C272 SCD1U16V2KX-3GP1 2
C273 SCD1U16V2KX-3GP1 2
TP58 TPAD28-1-GP-U1
C319
SC22U25V5MX-GP
1 2
C274 SCD1U16V2KX-3GP1 2
R412
0R2J-2-GP
12
R434
1KR2F-3-GP
1 2
R340
0R2J-2-GP
1 2
R481
0R2J-2-GP
1 2C269 SCD1U16V2KX-3GP1 2
C321
SC22U25V5MX-GP
1 2
C312 SCD047U25V2KX-GP1 2
C262 SCD1U16V2KX-3GP1 2
C280 SCD1U16V2KX-3GP1 2
R3960R2J-2-GP 12
U32
2N7002DW-7F-GP
NOPOP
1
2
3 4
5
6
C278 SCD1U16V2KX-3GP1 2
U31
SN74LVC1G07DCKRG4-2-GP
GND3 A2 NC#11 VCC 5
Y 4
C284 SCD1U16V2KX-3GP1 2
R4130R2J-2-GP 12
C308 SCD01U16V2KX-3GP12
C307 SCD01U16V2KX-3GP12
C281 SCD1U16V2KX-3GP1 2
R3820R2J-2-GP 12
C318
SC22U25V5MX-GP
1 2
R194
0R2J-2-GP
12
C305 SCD01U16V2KX-3GP12
C263 SCD1U16V2KX-3GP1 2
C287 SCD1U16V2KX-3GP1 2
C268 SCD1U16V2KX-3GP1 2
U34
2N7002DW-7F-GP
1
2
3 4
5
6
C276 SCD1U16V2KX-3GP1 2
C316 SCD047U25V2KX-GP1 2
C320
SC22U25V5MX-GP
1 2
C265 SCD1U16V2KX-3GP1 2
R445
4K7R2F-GP
1 2
BOTTOM TOP 
02 Do not mirror 
GF1
GF-PCIE-164P-15-GP
B1B1
B2B2
B3B3
B4B4
B5B5
B6B6
B7B7
B8B8
B9B9
B10B10
B11B11
B12B12
B13B13
B14B14
B15B15
B16B16
B17B17
B18B18
B19B19
B20B20
B21B21
B22B22
B23B23
B24B24
B25B25
B26B26
B27B27
B28B28
B29B29
B30B30
B31B31
B32B32
B33B33
B34B34
B35B35
B36B36
B37B37
B38B38
B39B39
B40B40
B41B41
B42B42
B43B43
B44B44
B45B45
B46B46
B47B47
B48B48
B49B49
B50B50
B51B51
B52B52
B53B53
B54B54
B55B55
B56B56
B57B57
B58B58
B59B59
B60B60
B61B61
B62B62
B63B63
B64B64
B65B65
B66B66
B67B67
B68B68
B69B69
B70B70
B71B71
B72B72
B73B73
B74B74
B75B75
B76B76
B77B77
B78B78
B79B79
B80B80
B81B81
B82B82
A1 A1
A2 A2
A3 A3
A4 A4
A5 A5
A6 A6
A7 A7
A8 A8
A9 A9
A10 A10
A11 A11
A12 A12
A13 A13
A14 A14
A15 A15
A16 A16
A17 A17
A18 A18
A19 A19
A20 A20
A21 A21
A22 A22
A23 A23
A24 A24
A25 A25
A26 A26
A27 A27
A28 A28
A29 A29
A30 A30
A31 A31
A32 A32
A33 A33
A34 A34
A35 A35
A36 A36
A37 A37
A38 A38
A39 A39
A40 A40
A41 A41
A42 A42
A43 A43
A44 A44
A45 A45
A46 A46
A47 A47
A48 A48
A49 A49
A50 A50
A51 A51
A52 A52
A53 A53
A54 A54
A55 A55
A56 A56
A57 A57
A58 A58
A59 A59
A60 A60
A61 A61
A62 A62
A63 A63
A64 A64
A65 A65
A66 A66
A67 A67
A68 A68
A69 A69
A70 A70
A71 A71
A72 A72
A73 A73
A74 A74
A75 A75
A76 A76
A77 A77
A78 A78
A79 A79
A80 A80
A81 A81
A82 A82
R443 0R2J-2-GP12



5
5
4
4
3
3
2
2
1
1
D D
C C
B B
A A
BMC_I2C_DATA
BMC_I2C_CLK
BMC_I2C_ALERT#
TEMP_1_ALERT#
SLOT_ID2
SLOT_ID1
SLOT_ID0
LPC_CPU_FRAME#
LPC_AD_2
LPC_AD_1
LPC_AD_3
LPC_AD_0
IRQ_LV_MCERR#
MEMORY_FPGA_HOT#
SMB_PECI_LV_DATA
SMB_PECI_LV_CLK
IRQ_CPU_SERIAL
IRQ_CPU_IERR#
CPU_ERR_N0
CPU_ERR_N1
PROCESSOR_HOT_LVC#
IRQ_NMI
PVCCP_PVNN_VRHOT#
CPU_THERMTRIP_LVC#
HEARTBEAT_LED
PORT80_BIT4
PORT80_BIT5
PORT80_BIT6
PORT80_BIT7
PORT80_BIT0
HOST_RSTBTN#
PORT80_BIT0 PORT80_R_BIT0
PORT80_BIT1 PORT80_R_BIT1
PORT80_BIT2 PORT80_R_BIT2
PORT80_BIT3 PORT80_R_BIT3
PORT80_BIT4 PORT80_R_BIT4
PORT80_BIT5 PORT80_R_BIT5
PORT80_BIT6 PORT80_R_BIT6
PORT80_BIT7 PORT80_R_BIT7
HEARTBEAT_LED HEARTBEAT_R_LED
BIOS_POST_COMPLETE_R
HOST_R_RSTBTN#
READY_R#
SMB_PECI_LV_DATA
SMB_PECI_LV_CLK
FPGA_SMB_HOST_DATA
FPGA_SMB_HOST_CLK
FPGA_SMB_HOST_DATA
FPGA_SMB_HOST_CLK
POWER_GOOD_R
TP_FPGA_P100
TP_FPGA_P84
TP_FPGA_P85
TP_FPGA_P110
TP_FPGA_P111
TP_FPGA_P112
TP_FPGA_P113
REV_CPU_FPGA_R_IO0
REV_CPU_FPGA_R_IO1
IRQ_CPU_LV_IERR#
IRQ_CPU_SERIAL
IRQ_LV_MCERR#
POWER_GOOD_R
HOST_R_RSTBTN#
POWER_CONTROL
HOST_LV_RSTBTN#
HOST_LV_D_RSTBTN#
PMU_SLP_R_S45#
PMU_PLD_R_PLTRST#
P3V3_STBY
P3V3_STBY
P3V3_STBY
P3V3_STBY
P3V3_STBY
P3V3_STBY
P3V3
P3V3_STBYP3V3_STBY
P3V3
PORT80_BIT139
PORT80_BIT239
PORT80_BIT339
FPGA_READY# 15
BIOS_POST_CMPLT# 14
CPU_THERMTRIP_LVC# 22
POWER_GOOD 53
PROCESSOR_HOT_LVC#22
MEMORY_FPGA_HOT#22
IRQ_LV_MCERR#53
IRQ_NMI15
CPU_ERR_N115,16
CPU_ERR_N015,16
IRQ_CPU_SERIAL15
IRQ_CPU_LV_IERR#53
SMB_PECI_LV_DATA22
SMB_PECI_LV_CLK22
LPC_CPU_LAD015
LPC_CPU_LAD115
LPC_CPU_LAD215
LPC_CPU_LAD315
LPC_CPU_FRAME#15,16
TEMP_1_ALERT#35
BMC_I2C_DATA35,39
BMC_I2C_CLK35,39
BMC_I2C_ALERT#35
LPC_CPU_CLKOUT015
PVCCP_PVNN_VRHOT#50,51
SLOT_ID037
SLOT_ID137
SLOT_ID237
REV_CPU_FPGA_IO017
REV_CPU_FPGA_IO117
FPGA_PWRBTN# 53
HOST_LV_RSTBTN#53
FPGA_SMB_HOST_DATA 22
FPGA_SMB_HOST_CLK 22
PMU_SLP_S45#15,16,22,51
PMU_PLTRST#15,34,37,53
Title 
Size Document Number R e v 
Date: Sheet 
o f 
Honey_Badger_uServer 1B
FPGA I/O PORT(1/3)
A3
38 56Tuesday, January 20, 2015
Wiwynn Incorporated
http://www.wiwynn.com
8F, 90, Sec.1, Xintai 5th Rd., Xizhi Dist.,
New Taipei City 22102, Taiwan (R.O.C.)
Title 
Size Document Number R e v 
Date: Sheet 
o f 
Honey_Badger_uServer 1B
FPGA I/O PORT(1/3)
A3
38 56Tuesday, January 20, 2015
Wiwynn Incorporated
http://www.wiwynn.com
8F, 90, Sec.1, Xintai 5th Rd., Xizhi Dist.,
New Taipei City 22102, Taiwan (R.O.C.)
Title 
Size Document Number R e v 
Date: Sheet 
o f 
Honey_Badger_uServer 1B
FPGA I/O PORT(1/3)
A3
38 56Tuesday, January 20, 2015
Wiwynn Incorporated
http://www.wiwynn.com
8F, 90, Sec.1, Xintai 5th Rd., Xizhi Dist.,
New Taipei City 22102, Taiwan (R.O.C.)
R151
300R2F-GP
1 2
TP14 TPAD28-1-GP-U1
R468
8K2R2F-1-GP
1 2
U30
2N7002DW-7F-GP
1
2
3 4
5
6
R149
300R2F-GP
1 2
R3033R2F-3-GP 12
R153
300R2F-GP
1 2
R2933R2F-3-GP 12
R141
4K7R2F-GP
1 2
R395 0R2J-2-GP1 2
TP21 TPAD28-1-GP-U1
R142 0R2J-2-GP1 2
R154
300R2F-GP
1 2
LED11
LED-YG-51-GP
AK
R470
4K7R2F-GP
1 2
R58 0R2J-2-GP1 2
R155
300R2F-GP
1 2
R152
300R2F-GP
1 2
R156
300R2F-GP
1 2
LED9
LED-YG-51-GP
AK
LED12
LED-YG-51-GP
AK
R466
4K7R2F-GP
1 2
R57
4K7R2F-GP
1 2
LED5
LED-YG-51-GP
AK
R52 0R2J-2-GP1 2
R26
4K7R2F-GP
1 2
2 OF 5 U14B
EP4CE6E22C8N-GP
IO#11
IO#22
IO#33
IO#10/DIFFIO_L4P/DQS0L/CQ1L/DPCLK010
IO#11/DIFFIO_L4N11
IO#32/RUP132
IO#33/RDN133
IO#28/DIFFIO_L6N28
IO#30/DIFFIO_L8P/DQS1L/CQ1L#/DPCLK130
IO#3434
IO#43/PLL1_CLKOUTP43
IO#44/PLL1_CLKOUTN44
IO#38/DIFFIO_B1P38
IO#39/DIFFIO_B1N39
IO#42/DQS1B/CQ1B#/DPCLK242
IO#49/DIFFIO_B9P/DQ1B49
IO#50/DIFFIO_B9N/DQ1B50
IO#51/DIFFIO_B10P/DQ1B51
IO#52/DIFFIO_B11P52
IO#53/DIFFIO_B11N53
IO#66/RUP2/DQ1B66
IO#67/RDN2/DQ1B67
IO#54/DIFFIO_B12P54
IO#55/DIFFIO_B12N55
IO#58/DIFFIO_B15P/DQ1B58
IO#59/DIFFIO_B16P/DQ1B59
IO#60/DIFFIO_B16N/DQ1B60
IO#6464
IO#68/DIFFIO_B20N/DQS0B/CQ1B/DPCLK368
IO#6969
IO#70/DIFFIO_B21P70
IO#71/DIFFIO_B21N71
IO#72/DIFFIO_B22P72
IO#76/RUP3 76
IO#77/RDN3 77
IO#73 73
IO#74 74
IO#75 75
IO#83 83
IO#84/DIFFIO_R8N 84
IO#85/DIFFIO_R8P/DQS1R/CQ1R#/DPCLK4 85
IO#100 100
IO#104/DQS0R/CQ1R/DPCLK5 104
IO#106/DIFFIO_R1N 106
IO#114/RUP4/DQ1T 114
IO#115/RDN4/DQ1T 115
IO#112/PLL2_CLKOUTN 112
IO#113/PLL2_CLKOUTP 113
IO#110/DIFFIO_T20P/DQS0T/CQ1T/DPCLK6 110
IO#111/DIFFIO_T19P 111
IO#120/DIFFIO_T16N/DQ1T 120
IO#121/DIFFIO_T16P 121
IO#124/DIFFIO_T13P 124
IO#125 125
IO#126/DIFFIO_T12N 126
IO#127/DIFFIO_T12P 127
IO#128/DIFFIO_T11N 128
IO#129/DIFFIO_T11P 129
IO#135/DIFFIO_T8N/DQ1T 135
IO#141/DIFFIO_T5P 141
IO#142/DIFFIO_T2P/DQS1T/CQ1T#/DPCLK7 142
IO#143/DIFFIO_T1N/DQ1T 143
IO#144/DIFFIO_T1P/DM1T 144
LED6
LED-YG-51-GP
AK
R506
1KR2F-3-GP
1 2
R27
4K7R2F-GP
1 2
TP12 TPAD28-1-GP-U1
R3133R2F-3-GP 12
R51
4K7R2F-GP
1 2
LED7
LED-YG-51-GP
AK
TP63 TPAD28-1-GP-U1
R3990R2J-2-GP NOPOP1 2
R482 0R2J-2-GP1 2
TP11 TPAD28-1-GP-U1
R140
4K7R2F-GP
1 2
R148
300R2F-GP
1 2
LED8
LED-YG-51-GP
AK
LED10
LED-YG-51-GP
AK
R474
4K7R2F-GP
1 2
R483 0R2J-2-GP1 2
C323
SCD1U10V2KX-5GP
1 2
R467
4K7R2F-GP
1 2
R2833R2F-3-GP 12
R150
300R2F-GP
1 2
R3970R2J-2-GP NOPOP1 2
R48 0R2J-2-GP1 2
TP13 TPAD28-1-GP-U1
R147
4K7R2F-GP
NOPOP
1 2
TP62 TPAD28-1-GP-U1
LED4
LED-YG-51-GP
AK



5
5
4
4
3
3
2
2
1
1
D D
C C
B B
A A
ADD=0101000 (0x50) 
I2C to SPI SW 
LPC_CPU_CLKRUN#
CPU_ERR_N2
PORT80_BIT1
SLOT_ID3
JTAG_PLD_TCK
JTAG_PLD_TDI
JTAG_PLD_TDO
JTAG_PLD_TMS
JTAG_PLD_TDI
JTAG_PLD_TCK
JTAG_PLD_TMS
FPGA_DCLK
C_NCONFIG#
C_NSTATUS#
C_CONF_DONE
C_NCE#
MSEL0
MSEL1
MSEL2
MSEL0
MSEL1
MSEL2
C_DCLK
C_CONF_DONE
C_NSTATUS#
FPGA_DATA0
FPGA_ASDO
C_DATA0
C_CEO#
FPGA_CSO#
C_NSTATUS#C_LED_NSTATUS#
DISABLEPORT80_BIT2
PORT80_BIT3
DISABLE
OSC_5M_CLK_R
C_R_CSO#
C_R_DATA0
C_R_DCLK
C_NCE#
C_CSO#
C_ASDO
C_DCLK
C_CONF_DONE
C_NCONFIG#
C_DATA0
DISABLE_H
C_NCE_R#
JTAG_CPU_PLD_TDO
C_NCE#
FPGA_CLK_DP
OSC_5M_EN
JTAG_CPU_PLD_TDO JTAG_PLD_TDO
JTAG_PLD_TMS
JTAG_PLD_TDI
JTAG_PLD_TCK
JTAG_CPU_PLD_TDO
C_R_ASDO
C_NCONFIG#
SPI_SW_NCONFIG#
SPI_SW_ADDR0
SPI_SW_ADDR1
SPI_SW_ADDR0
SPI_SW_ADDR2
SPI_SW_ADDR1
SPI_SW_ADDR2
SPI_SW_DCLKSPI_SW_DATA0
SPI_SW_ASDO
SPI_SW_CSO#
SPI_SW_NCONFIG#
SPI_SW_INT#
SPI_SW_RST#
C_CSO#
C_DATA0
C_DCLK
C_ASDO
C_DATA0
C_ASDO
C_CSO#
C_DCLK
FPGA_CSO#
SPI_SW_CSO#
SPI_SW_DCLK
FPGA_DCLK
SPI_SW_ASDO
FPGA_ASDO
SPI_SW_DATA0
FPGA_DATA0
BUS_SW_SEL
BUS_SW_OE#
P3V3_STBY P3V3_STBY
P3V3_STBY
P3V3_STBY
P3V3_STBY
P3V3_STBY
P3V3_STBY P3V3_STBY
P3V3_STBY
P3V3_STBY
P3V3_STBYP3V3_STBY P3V3_STBY
P3V3_STBY
P3V3_STBY
P3V3_STBY
CPU_ERR_N215,16
LPC_CPU_CLKRUN#15,16
SLOT_ID337
PORT80_BIT138
PORT80_BIT238
PORT80_BIT338
JTAG_PLD_TCK 36
JTAG_PLD_TMS 36
JTAG_PLD_TDO 36
CPU_FPGA_DISABLE 15
JTAG_CPU_PLD_TDO36
JTAG_RST# 36
BMC_I2C_DATA35,38
BMC_I2C_CLK35,38
CPU_RSMRST# 15,16,24,35,37,46
Title 
Size Document Number R e v 
Date: Sheet 
o f 
Honey_Badger_uServer 1B
FPGA I/O PORT(2/3)
Custom
39 56Tuesday, January 20, 2015
Wiwynn Incorporated
http://www.wiwynn.com
8F, 90, Sec.1, Xintai 5th Rd., Xizhi Dist.,
New Taipei City 22102, Taiwan (R.O.C.)
Title 
Size Document Number R e v 
Date: Sheet 
o f 
Honey_Badger_uServer 1B
FPGA I/O PORT(2/3)
Custom
39 56Tuesday, January 20, 2015
Wiwynn Incorporated
http://www.wiwynn.com
8F, 90, Sec.1, Xintai 5th Rd., Xizhi Dist.,
New Taipei City 22102, Taiwan (R.O.C.)
Title 
Size Document Number R e v 
Date: Sheet 
o f 
Honey_Badger_uServer 1B
FPGA I/O PORT(2/3)
Custom
39 56Tuesday, January 20, 2015
Wiwynn Incorporated
http://www.wiwynn.com
8F, 90, Sec.1, Xintai 5th Rd., Xizhi Dist.,
New Taipei City 22102, Taiwan (R.O.C.)
R339
1KR2F-3-GP
NOPOP
1 2
TP15
TPAD32-GP1
R297
0R2J-2-GP
NOPOP
1 2
R493
1KR2F-3-GP
NOPOP
1 2
R177
10KR2F-2-GP
1 2
C358
SCD1U16V2KX-3GP
1 2
R414 0R2J-2-GP
NOPOP1 2
R484
10KR2F-2-GP
1 2
R13010KR2F-2-GP 1 2
C357
SC1U6D3V3KX-2GP
1 2
R123
10KR2F-2-GP
1 2
R89
300R2F-GP
12
R175
0R2J-2-GP
NOPOP
1 2
R164
10KR2F-2-GP
1 2
TP42 TPAD32-GP1
TP40 TPAD32-GP1
R224
10KR2F-2-GP
1 2
R494
0R2J-2-GP
1 2
R182
33R2F-3-GP
1 2
R74
4K7R2F-GP
1 2
TP37
TPAD32-GP
1
R336
1KR2F-3-GP
1 2
R338
1KR2F-3-GP
1 2
R471
1KR2F-3-GP
1 2
SW2
SW-DIP-2P-1-GP
NOPOP
1 2
R87
4K7R2F-GP
1 2
R791KR2F-3-GP 12
R188
33R2F-3-GP
1 2
R29033R2F-3-GP 1 2
R163
1KR2F-3-GP
1 2
TP39 TPAD32-GP1
U17
W25Q64FVZPIG-GP
CS#1
DO/IO12
WP#/IO23
GND4
VCC 8
HOLD#/IO3 7
CLK 6
DI/IO0 5
GND 9
R97
0R2J-2-GP
1 2
TP41 TPAD32-GP1
R433
1KR2F-3-GP
NOPOP
1 2
TP43 TPAD32-GP1
R7810KR2F-2-GP 1 2
C311
SCD1U16V2KX-3GP
1 2
TP17
TPAD32-GP1
4 OF 5 U14D
EP4CE6E22C8N-GP
IO#13/DATA013
IO#6/DIFFIO_L1N/DATA1/ASDO6
IO#132/DIFFIO_T10N/DATA2/DQ1T132
IO#133/DIFFIO_T10P/DATA3/DQ1T133
IO#137/DATA5/DQ1T137
IO#138/DATA6138
IO#103/DIFFIO_R3P/CLKUSR103
IO#99/DIFFIO_R4P/CRC_ERROR99
IO#87/DIFFIO_R7P/DEV_CLR#87
IO#86/DIFFIO_R7N/DEV_OE86
IO#8/DIFFIO_L2P/FLASH_CE#/CSO#8
IO#98/DIFFIO_R4N/INIT_DONE98
IO#101/DIFFIO_R3N/CEO#101
CONF_DONE 92
DCLK 12
MSEL0 94
MSEL1 96
MSEL2 97
CE# 21
CONFIG# 14
STATUS# 9
TCK 16
TDI 15
TDO 20
TMS 18
R28633R2F-3-GP 1 2
R77
10KR2F-2-GP
1 2
3 OF 5 U14C
EP4CE6E22C8N-GP
IO#7/VREFB1N07
IO#31/VREFB2N031
IO#46/VREFB3N046
IO#65/VREFB4N065
IO#80/VREFB5N080
IO#105/VREFB6N0105
IO#119/VREFB7N0119
IO#136/VREFB8N0136
CLK1/DIFFCLK_0N 23
CLK2/DIFFCLK_1P 24
CLK3/DIFFCLK_1N 25
CLK4/DIFFCLK_2P 91
CLK5/DIFFCLK_2N 90
CLK6/DIFFCLK_3P 89
CLK7/DIFFCLK_3N 88
LED2
LED-YG-51-GP
A K
TP18
TPAD32-GP1
C356
SCD1U16V2KX-3GP
1 2
R91
4K7R2F-GP
1 2
TP16
TPAD32-GP1
R104
0R2J-2-GP
1 2
CN3
FOX-CONN10A-S8-GP
1
3
5
7
9
4
6
8
10
2
U48
SC18IS602BIPW-GP
RESET# 3
MISO5
SCL8
A014
A115
A216 SS0#/GPIO0 1
SS1#/GPIO1 2
SDA7
SS2#/GPIO2 10
SS3#/GPIO3 13
MOSI6
INT# 9
SPICLK 11
VSS 4
VDD12
SW1
SW-PUSH-2P-6-GP
NOPOP
21
U50
74CBTLV3257RG-1GP
S 1
1B1 2 1B2 3
1A 42B15
2B26 2A 7
GND 8
3A 9
3B210 3B111
4A 12
4B213 4B114
OE# 15 VCC 16 
GND 17 
C137
SC1U6D3V2KX-GP
12
C21
SCD1U10V2KX-5GP
12
LED3
LED-YG-51-GP
A K
R492
1KR2F-3-GP
NOPOP
1 2
R100
0R2J-2-GP
1 2
TP8TPAD28-1-GP-U 1
R75
10KR2F-2-GP
1 2
R86 33R2F-3-GP1 2
OSC1
OSC-5MHZ-GP
E/D1
GND2 OUTPUT 3VDD 4
TP38 TPAD32-GP1
R76
10KR2F-2-GP
1 2
R131
300R2F-GP
12
R118
0R2J-2-GP
1 2
R801KR2F-3-GP 12



5
5
4
4
3
3
2
2
1
1
D D
C C
B B
A A
0.1uF x6 
0.1uF x4 
0.1uF x15 
0.1uF x4 
P1V2_FPGA_D P3V3_STBY
P2V5_STBY
P1V2_FPGA_D
P3V3_STBY
P1V2_FPGA_A
P2V5_STBY
P1V2_FPGA_A
Title 
Size Document Number Rev 
Date: Sheet o f 
Honey_Badger_uServer 1B
FPGA POWER&GND (3/3)
A4
40 56Tuesday, January 20, 2015
Wiwynn Incorporated
http://www.wiwynn.com
8F, 90, Sec.1, Xintai 5th Rd., Xizhi Dist.,
New Taipei City 22102, Taiwan (R.O.C.)
Title 
Size Document Number Rev 
Date: Sheet o f 
Honey_Badger_uServer 1B
FPGA POWER&GND (3/3)
A4
40 56Tuesday, January 20, 2015
Wiwynn Incorporated
http://www.wiwynn.com
8F, 90, Sec.1, Xintai 5th Rd., Xizhi Dist.,
New Taipei City 22102, Taiwan (R.O.C.)
Title 
Size Document Number Rev 
Date: Sheet o f 
Honey_Badger_uServer 1B
FPGA POWER&GND (3/3)
A4
40 56Tuesday, January 20, 2015
Wiwynn Incorporated
http://www.wiwynn.com
8F, 90, Sec.1, Xintai 5th Rd., Xizhi Dist.,
New Taipei City 22102, Taiwan (R.O.C.)
C74 SCD1U10V2KX-5GP1 2
C232 SCD1U10V2KX-5GP1 2
C134 SCD1U10V2KX-5GP1 2
C164 SCD1U10V2KX-5GP1 2
5 OF 5 U14E
EP4CE6E22C8N-GP
GND4
GND19
GND22
GND27
GND41
GND48
GND57
GND63
GND79
GND82
GND 95
GND 118
GND 123
GND 131
GND 140
GNDA1 36
GNDA2 108
GND 145
C136 SCD1U10V2KX-5GP1 2
C233 SCD1U10V2KX-5GP1 2
C236 SCD1U10V2KX-5GP1 2
C149 SCD1U10V2KX-5GP1 2
C162 SCD1U10V2KX-5GP1 2
C139 SCD1U10V2KX-5GP1 2
C13 SCD1U10V2KX-5GP1 2
C197 SCD1U10V2KX-5GP1 2
C49 SCD1U10V2KX-5GP1 2
C73 SCD1U10V2KX-5GP1 2
C46 SCD1U10V2KX-5GP1 2
C11 SCD1U10V2KX-5GP1 2
C235 SCD1U10V2KX-5GP1 2
C172 SCD1U10V2KX-5GP1 2
C138 SCD1U10V2KX-5GP1 2
C18 SCD1U10V2KX-5GP1 2
C165 SCD1U10V2KX-5GP1 2
C144 SCD1U10V2KX-5GP1 2
C234 SCD1U10V2KX-5GP1 2
1 OF 5 U14A
EP4CE6E22C8N-GP
VCCINT29
VCCINT45
VCCINT61
VCCINT78
VCCINT102
VCCINT116
VCCINT134
VCCA135
VCCA2107
VCCD_PLL137
VCCD_PLL2109
VCCIO1 17
VCCIO2 26
VCCIO3 40
VCCIO3 47
VCCIO4 56
VCCIO4 62
VCCIO5 81
VCCIO6 93
VCCIO7 117
VCCIO7 122
VCCIO8 130
VCCIO8 139
VCCINT5
C192 SCD1U10V2KX-5GP1 2
C140 SCD1U10V2KX-5GP1 2
C135 SCD1U10V2KX-5GP1 2
C12 SCD1U10V2KX-5GP1 2
C223 SCD1U10V2KX-5GP1 2
C54 SCD1U10V2KX-5GP1 2



5
5
4
4
3
3
2
2
1
1
D D
C C
B B
A A
I_rated=6A 
DCR=20mohm 
Z=22ohm 
FCCM Mode 
Vout=0.6x(1+Ru/Rd)=2.496 
Power rail : P3V3_STBY(3.3V) 
Controller : TPS53318 (Fswitching=500KHz) 
TDC : 3.24A 
MAX : 4.5A 
OCP : 7A 
SS=5.6ms 
OCP = 8.5A 
FS=500KHz 
2.16v 
1016_power 
P3V3_STBYP3V3_STBY_ROVP
P3V3_STBY_VREG
P3V3_STBY_LL
P3V3_STBY_EN
P3V3_STBY_RF
P3V3_STBY_VREG
P3V3_STBY_TRIP
P3V3_STBY_VBST 
P3V3_STBY_MODE
P3V3_STBY_OUT
P3V3_STBY_VBST_RC
P3V3_STBY_VDD
P3V3_STBY_SNB
P3V3_STBY_VFB_R P3V3_STBY_VFB
P3V3_STBY_LL_R
P3V3_STBY_VIN
P3V3_STBY
P12V
AGND_P3V3_STBY
AGND_P3V3_STBY
AGND_P3V3_STBY
AGND_P3V3_STBY
P12V
AGND_P3V3_STBY
P12V
AGND_P3V3_STBY
P3V3_STBY_VREG
P3V3_STBY_PG42
Title 
Size Document Number R e v 
Date: Sheet 
o f 
Honey_Badger_uServer 1B
PWRSW_P3V3_STBY
A3
41 56Tuesday, January 20, 2015
Wiwynn Incorporated
http://www.wiwynn.com
8F, 90, Sec.1, Xintai 5th Rd., Xizhi Dist.,
New Taipei City 22102, Taiwan (R.O.C.)
Title 
Size Document Number R e v 
Date: Sheet 
o f 
Honey_Badger_uServer 1B
PWRSW_P3V3_STBY
A3
41 56Tuesday, January 20, 2015
Wiwynn Incorporated
http://www.wiwynn.com
8F, 90, Sec.1, Xintai 5th Rd., Xizhi Dist.,
New Taipei City 22102, Taiwan (R.O.C.)
Title 
Size Document Number R e v 
Date: Sheet 
o f 
Honey_Badger_uServer 1B
PWRSW_P3V3_STBY
A3
41 56Tuesday, January 20, 2015
Wiwynn Incorporated
http://www.wiwynn.com
8F, 90, Sec.1, Xintai 5th Rd., Xizhi Dist.,
New Taipei City 22102, Taiwan (R.O.C.)
PR192
3K9R2F-GP
1 2
PC73
SC100U6D3V6MX-GP 
1206
X5R
1 2
PR193
3D01R5F-GP
1 2
PC181
SCD1U25V2KX-2-GP 
1 2
PR196
10KR2F-2-GP
POP
12
PC188
SC4D7U25V5KX-1-GP
1 2
PC182
SC22U25V5MX-GP 
1 2
PU15
TPS53318DQPR-GP
VFB 1PGOOD3
EN2
VBST 4
ROVP 5
LL#6 6
LL#7 7
LL#8 8
LL#9 9
LL#10 10
LL#11 11
VIN 12 VIN 13 VIN 14 VIN 15 VIN 16 VIN 17 
VREG18
VDD19
MODE20
TRIP21
RF22
GND 23 
PR206 866KR2F-GPNOPOP1 2
PR204 475KR2F-GP1 2
PC173
SC1U10V2KX-1GP
NOPOP
1 2
PC152
SCD1U25V2KX-2-GP
1 2
PR197
3D01R5F-GP
NOPOP
1 2
PC151
SC1U10V2KX-1GP 
NOPOP12
PC164
SCD1U50V3KX-GP 
1 2
PC172 SC1U10V2KX-1GP
NOPOP
1 2
PC176
SC2K2P50V3KX-GP
NOPOP
1 2
PC184
SC22U25V5MX-GP 
1 2
PC187
SC22U25V5MX-GP 
1 2
PC159
SC4D7U25V5KX-1-GP
1 2
PR202 73K2R2F-GP1 2
PR194
0R6J-3-GP
1 2
PC185 SC1U10V2KX-1GP1 2
PR203 100KR2F-L1-GPNOPOP1 2
PR207
10KR2F-2-GP
12
PR201 619KR2F-GPNOPOP1 2
PG6
COPPER-CLOSE-GP-U
1 2
PC149
SC22U6D3V3MX-1-GP 
1 2
PR198 44K2R2F-1-GP1 2
PC77
SC100U6D3V6MX-GP 
1206
X5R
1 2
PR209
2D2R3J-2-GP
12
PR190 0R2J-2-GP
NOPOP
1 2
PR195
15KR2F-GP
1 2
PL9
BLM21PG220SN1DGP
1 2
PC186
SC22U25V5MX-GP 
1 2
PC150
SCD1U25V2KX-2-GP 
1 2
PR199
10KR2F-2-GP 
1 2
PL6
IND-2D2UH-122-GP
1 2
PR200
10R3F-GP
1 2
PC174
SC1KP50V2KX-1GP
1 2
PC80
SC100U6D3V6MX-GP 
1206
X5R
1 2
PR189
0R2J-2-GP 
1 2
PR191
0R6J-3-GP
1 2R319
2K2R2F-GP
POP
12



5
5
4
4
3
3
2
2
1
1
D D
C C
B B
A A
Id= 2.7A 
Power rail : P1V8_STBY 
Controller : EP53F8QI (Fswitching=4MHz) 
TDC :1.04A 
MAX :1.04A 
OCP :3.2A 
SW_P1V8_EN_S
SW_P1V8_EN_G
SW_P1V8_EN_LV
P1V8_B
VR_FB_R_P1V8_STBY
VR_PVIN_P1V8_STBY
VR_FB_P1V8_STBYP1V8_STBY_PG
P1V8_STBY_VOUT
VR_EN_P1V8_STBY
VR_AVIN_R_P1V8_STBY VR_AVIN_P1V8_STBY
P1V8_G
P1V8_STBY
P1V8
P3V3_STBY P12VP3V3_STBY
P3V3_STBY
P1V8
P1V8_STBY
P3V3_STBY
AGND_P1V8_STBY
AGND_P1V8_STBY
AGND_P1V8_STBY
P3V3_STBY
AGND_P1V8_STBY
P3V3_STBY
PWRGD_P1V0_PG49
P3V3_STBY_PG41
P1V8_STBY_PG43
PWRGD_P1V8_PG 46
Title 
Size Document Number R e v 
Date: Sheet 
o f 
Honey_Badger_uServer 1B
PWRSW_P1V8_STBY & P1V8
A3
42 56Tuesday, January 20, 2015
Wiwynn Incorporated
http://www.wiwynn.com
8F, 90, Sec.1, Xintai 5th Rd., Xizhi Dist.,
New Taipei City 22102, Taiwan (R.O.C.)
Title 
Size Document Number R e v 
Date: Sheet 
o f 
Honey_Badger_uServer 1B
PWRSW_P1V8_STBY & P1V8
A3
42 56Tuesday, January 20, 2015
Wiwynn Incorporated
http://www.wiwynn.com
8F, 90, Sec.1, Xintai 5th Rd., Xizhi Dist.,
New Taipei City 22102, Taiwan (R.O.C.)
Title 
Size Document Number R e v 
Date: Sheet 
o f 
Honey_Badger_uServer 1B
PWRSW_P1V8_STBY & P1V8
A3
42 56Tuesday, January 20, 2015
Wiwynn Incorporated
http://www.wiwynn.com
8F, 90, Sec.1, Xintai 5th Rd., Xizhi Dist.,
New Taipei City 22102, Taiwan (R.O.C.)
PC121
SC680P50V2KX-2GP
1 2
R239
1KR2F-3-GP
12
R256
4K02R2F-GP
NOPOP
12
PR184
118KR3B-GP
1 2
Q10
2N7002A-7-GP
G
SD
PC123
SC22U6D3V5MX-2GP 
1 2
Q9
2N7002A-7-GP
G
S D
PC124
SC22U6D3V5MX-2GP 
1 2
Q7
MMBT3904TT1G-GP
C
B
E
PR181
0R3J-6-GP
1 2
PR180
0R2J-2-GP
12
PG5
COPPER-CLOSE-GP-U
1 2
R255
1KR2F-3-GP
1 2
R250
10KR2F-2-GP
1 2
Q8
FDN359BN-GP-U
G
D S
PC126
SC5P50V2CN-2GP
1 2
C113
SCD47U25V2KX-GP
1 2
PR183
237KR2F-GP
1 2
PC127
SC1U16V3KX-5GP 
1 2
PR173
0R3J-6-GP
1 2
PU13
EP53F8QI-T-GP
NC#1/SW 1
PGND 2
NC#15/SW 15 
NC#16/SW 16 
PGND 3
AVIN24
VOUT 8
AGND 9
AVIN110
POK11 VFB 5
NC#6 6
VOUT 7
PVIN13
PVIN14
ENABLE12
PR172
10KR2F-2-GP
12
PR176
10R2F-L-GP
1 2
R257
0R2J-2-GP
12
R240
1KR2F-3-GP
1 2
PR171
0R2J-2-GP
1 2
PC120
SC22U6D3V5MX-2GP 
1 2
R253
1KR2F-3-GP
1 2R254
4K02R2F-GP
12



5
5
4
4
3
3
2
2
1
1
D D
C C
B B
A A
Power rail :P1V5_STBY 
Controller :TPS74801 
TDC :0.415A 
Max :0.415A 
OCP:2A 
P1V5_STBY_FB
P1V5_STBY_BIAS
P1V5_STBY_SS
P1V5_STBY_EN
P1V5_STBY_OUTP1V5_STBY_IN
P3V3_STBY
P3V3_STBY
P3V3_STBY
P1V5_STBY
P1V8_STBY
P1V5_STBY_PG 45
P1V8_STBY_PG42
Title 
Size Document Number Rev 
Date: Sheet o f 
Honey_Badger_uServer 1B
PWR_1V5_STBY
A4
43 56Tuesday, January 20, 2015
Wiwynn Incorporated
http://www.wiwynn.com
8F, 90, Sec.1, Xintai 5th Rd., Xizhi Dist.,
New Taipei City 22102, Taiwan (R.O.C.)
Title 
Size Document Number Rev 
Date: Sheet o f 
Honey_Badger_uServer 1B
PWR_1V5_STBY
A4
43 56Tuesday, January 20, 2015
Wiwynn Incorporated
http://www.wiwynn.com
8F, 90, Sec.1, Xintai 5th Rd., Xizhi Dist.,
New Taipei City 22102, Taiwan (R.O.C.)
Title 
Size Document Number Rev 
Date: Sheet o f 
Honey_Badger_uServer 1B
PWR_1V5_STBY
A4
43 56Tuesday, January 20, 2015
Wiwynn Incorporated
http://www.wiwynn.com
8F, 90, Sec.1, Xintai 5th Rd., Xizhi Dist.,
New Taipei City 22102, Taiwan (R.O.C.)
PC132
SC470P50V2KX-3GP
1 2
PR187
0R3J-6-GP
1 2
PR182
0R2J-2-GP
1 2
PC129 
SC10U6D3V5KX-4GP 
1 2
PC131
SCD1U16V2KX-3GP
NOPOP
1 2
PU14
TPS74801RGW-GP
OUT#1 1
NC#2 2
NC#3 3
NC#4 4
IN#55 IN#66 IN#77 IN#88
PG 9
BIAS 10 
EN 11 
GND 12 
NC#13 13 
NC#14 14 
SS 15 
FB 16 
NC#17 17 
OUT#18 18
OUT#19 19
OUT#20 20
GND 21 
PR177
10KR2F-2-GP
12
PR185
4K75R2F-1-GP
1 2
PR179
0R3J-6-GP
1 2
PR178
0R2J-2-GP
1 2
R252
4K75R2F-1-GP
NOPOP
1 2
PC125
SCD1U16V2KX-3GP
1 2
PC130 
SC10U6D3V5KX-4GP 
1 2
PC137
SC1KP50V2KX-1GP 
NOPOP
1 2
PR186
4K22R2F-GP
1 2
PC138
SCD1U10V2KX-5GP
1 2
PC139
SC10U6D3V5KX-4GP 
1 2
PC134
SC10U6D3V5KX-4GP 
1 2
PC128
SCD1U16V2KX-3GP 
X7R
0.1uF
16V
0402
1 2
PC133
SC10U6D3V5KX-4GP 
1 2
PC141
SC10U6D3V5KX-4GP 
1 2



5
5
4
4
3
3
2
2
1
1
D D
C C
B B
A A
Power rail :P1V2_STBY(1.2V) 
Controller :LD1117AG 
TDC :0.2A 
Max :0.2A 
Power rail :P2V5_STBY 
Controller :TPS79301 
TDC : 0.034A 
Max :0.034A 
P1V8_STBY_LDO_IN1 P1V8_STBY_LDO_IN2
P1V2_STBY_LDO_OUT1 P1V2_STBY_LDO_OUT2
P2V5_STBY_OUT
P2V5_STBY_BYPASS
P2V5_STBY_FB
P3V3_STBY
P1V2_FPGA_A
P3V3_STBY
P1V2_FPGA_D
P2V5_STBY
P3V3_STBY
Title 
Size Document Number R e v 
Date: Sheet 
o f 
Honey_Badger_uServer 1B
PWR_2V5&1V2_STBY
A3
44 56Tuesday, January 20, 2015
Wiwynn Incorporated
http://www.wiwynn.com
8F, 90, Sec.1, Xintai 5th Rd., Xizhi Dist.,
New Taipei City 22102, Taiwan (R.O.C.)
Title 
Size Document Number R e v 
Date: Sheet 
o f 
Honey_Badger_uServer 1B
PWR_2V5&1V2_STBY
A3
44 56Tuesday, January 20, 2015
Wiwynn Incorporated
http://www.wiwynn.com
8F, 90, Sec.1, Xintai 5th Rd., Xizhi Dist.,
New Taipei City 22102, Taiwan (R.O.C.)
Title 
Size Document Number R e v 
Date: Sheet 
o f 
Honey_Badger_uServer 1B
PWR_2V5&1V2_STBY
A3
44 56Tuesday, January 20, 2015
Wiwynn Incorporated
http://www.wiwynn.com
8F, 90, Sec.1, Xintai 5th Rd., Xizhi Dist.,
New Taipei City 22102, Taiwan (R.O.C.)
PR228
30K1R2F-L-GP
1 2
PC212
SC4D7U10V3KX-GP
1 2
PR226
0R3J-6-GP
12
PU9
LD1117AG-12-AA3-A-R-GP
GND 1VOUT 2VIN 3
PU17
TPS79301DBVR-GP
IN1
GND2
EN3 BYPASS 4FB 5OUT 6
PC96
SC22U6D3V5MX-2GP
1 2
PC210
SC22P50V2GN-GP
1 2
PC209
SC1U6D3V2KX-GP
1 2
PR132
0R3J-6-GP
12
PC83
SC22U6D3V5MX-2GP
1 2
PC88
SC10U6D3V5KX-4GP
1 2
PC211
SCD01U16V2KX-3GP
1 2
PR107
0R3J-6-GP
1 2
PR146
0R3J-6-GP
12
PC98
SC10U6D3V5KX-4GP
1 2
PU8
LD1117AG-12-AA3-A-R-GP
GND 1VOUT 2VIN 3
PR136
0R3J-6-GP
1 2
PR227
31K6R2F-GP
1 2



5
5
4
4
3
3
2
2
1
1
D D
C C
B B
A A
Power rail : P1V0_STBY 
Controller : EP53F8QI (Fswitching=4MHz) 
TDC :1.2A 
MAX :1.2A 
OCP :3.2A 
VR_PVIN_P1V0_STBY
VR_FB_P1V0_STBYP1V0_STBY_PG
P1V0_STBY_VOUT
VR_EN_P1V0_STBY
VR_AVIN_R_P1V0_STBY VR_AVIN_P1V0_STBY
VR_FB_R_P1V0_STBY
P1V0_STBY
P3V3_STBY
AGND_P1V0_STBY
AGND_P1V0_STBY
AGND_P1V0_STBY
AGND_P1V0_STBY
P3V3_STBY P1V5_STBY_PG43
P1V0_STBY_PG46
Title 
Size Document Number R e v 
Date: Sheet 
o f 
Honey_Badger_uServer 1B
PWRSW_P1V0_STBY
A3
45 56Tuesday, January 20, 2015
Wiwynn Incorporated
http://www.wiwynn.com
8F, 90, Sec.1, Xintai 5th Rd., Xizhi Dist.,
New Taipei City 22102, Taiwan (R.O.C.)
Title 
Size Document Number R e v 
Date: Sheet 
o f 
Honey_Badger_uServer 1B
PWRSW_P1V0_STBY
A3
45 56Tuesday, January 20, 2015
Wiwynn Incorporated
http://www.wiwynn.com
8F, 90, Sec.1, Xintai 5th Rd., Xizhi Dist.,
New Taipei City 22102, Taiwan (R.O.C.)
Title 
Size Document Number R e v 
Date: Sheet 
o f 
Honey_Badger_uServer 1B
PWRSW_P1V0_STBY
A3
45 56Tuesday, January 20, 2015
Wiwynn Incorporated
http://www.wiwynn.com
8F, 90, Sec.1, Xintai 5th Rd., Xizhi Dist.,
New Taipei City 22102, Taiwan (R.O.C.)
PC100
SC22U6D3V5MX-2GP 
1 2
PR153
0R3J-6-GP
1 2
PR152
0R2J-2-GP
1 2
PR157
0R2J-2-GP
12
PR151
237KR2F-GP
1 2
PR159
10R2F-L-GP
1 2
PR163
0R3J-6-GP
1 2
PC110
SC1U16V3KX-5GP 
1 2
PC113
SC22U6D3V5MX-2GP 
1 2
PC104
SC5P50V2CN-2GP
1 2
PR155
10KR2F-2-GP
12
PU11
EP53F8QI-T-GP
NC#1/SW 1
PGND 2
NC#15/SW 15 
NC#16/SW 16 
PGND 3
AVIN24
VOUT 8
AGND 9
AVIN110
POK11 VFB 5
NC#6 6
VOUT 7
PVIN13
PVIN14
ENABLE12
PR147
348KR2F-GP
1 2
PC101
SC680P50V2KX-2GP 
1 2
PC112
SC22U6D3V5MX-2GP 
1 2
PG4
COPPER-CLOSE-GP-U
1 2



5
5
4
4
3
3
2
2
1
1
D D
C C
B B
A A
SW_P3V3_EN_LV_D
SW_P3V3_CPU_EN_LV_D
SW_P3V3_CPU_LV_G2
SW_P3V3_CPU_LV_G5 
SW_P3V3_EN_G2
SW_P3V3_LV_G5 
P3V3_CPU_PG_S2
P3V3_CPU_PG_S1
P3V3_CPU_DELAY_IN
CLK_GEN_DELAY1_PG
CLK_GEN_DELAY0_PG
SW_P3V3_LV_G5
P3V3_DISCHARGE_D
CLK_GEN_DELAY2_PG
P3V3_STBY
P12V
P3V3_STBY
P3V3_CPU
P12V
P12V
P12V
P3V3_STBYP3V3_STBY
P3V3_CPU
P3V3P3V3
P3V3
P3V3
PWRGD_P1V8_PG42
P1V0_STBY_PG45
CPU_RSMRST# 15,16,24,35,37,39
CLK_GEN_PG 22,31,32,53
Title 
Size Document Number R e v 
Date: Sheet 
o f 
Honey_Badger_uServer 1B
PWRSW_P3V3
A3
46 56Tuesday, January 20, 2015
Wiwynn Incorporated
http://www.wiwynn.com
8F, 90, Sec.1, Xintai 5th Rd., Xizhi Dist.,
New Taipei City 22102, Taiwan (R.O.C.)
Title 
Size Document Number R e v 
Date: Sheet 
o f 
Honey_Badger_uServer 1B
PWRSW_P3V3
A3
46 56Tuesday, January 20, 2015
Wiwynn Incorporated
http://www.wiwynn.com
8F, 90, Sec.1, Xintai 5th Rd., Xizhi Dist.,
New Taipei City 22102, Taiwan (R.O.C.)
Title 
Size Document Number R e v 
Date: Sheet 
o f 
Honey_Badger_uServer 1B
PWRSW_P3V3
A3
46 56Tuesday, January 20, 2015
Wiwynn Incorporated
http://www.wiwynn.com
8F, 90, Sec.1, Xintai 5th Rd., Xizhi Dist.,
New Taipei City 22102, Taiwan (R.O.C.)
R54
0R2J-2-GP
1 2
R46
10KR2F-2-GP
1 2
S
S
S
GD
D
D
D
Q4
AO4406AL-GP
1
2
3
45
6
7
8
U12
SN74LVC1G14DCKR-GP
NC#11
A2
GND3 Y 4
VCC 5
U7
SN74LVC1G14DCKR-GP
NC#11
A2
GND3 Y 4
VCC 5
R88
1KR2F-3-GP
12
R42
1KR2F-3-GP
1 2
R501
150R3F-GP
1 2
C20
SC1U25V3KX-GP
1 2
R64
4K7R2F-GP
1 2
C17
SCD47U25V2KX-GP
1 2
R65
33R2F-3-GP
1 2
C29
SCD1U10V2KX-5GP
1 2
Q17
2N7002A-7-GP
G
SD
R500
150R3F-GP
1 2
C27
SCD1U10V2KX-5GP
1 2
C16
SC1U25V3KX-GP
1 2
R63
10KR2F-2-GP
1 2
R69
8K2R2F-1-GP
1 2
R41
4K7R2F-GP
1 2
C19
SCD47U25V2KX-GP
1 2
R59
33R2F-3-GP
1 2
C28
SCD1U10V2KX-5GP
1 2
Q3
FDN359BN-GP-U
G
D S
C23
SCD1U10V2KX-5GP
1 2
C22
SC1U10V2KX-1GP
1 2
U8
2N7002DW-7F-GP
1
2
34
5
6
U11
2N7002DW-7F-GP
1
2
34
5
6 R53
10KR2F-2-GP
1 2
C14
SC1U10V2KX-1GP
1 2
U6
SN74LVC1G14DCKR-GP
NC#11
A2
GND3 Y 4
VCC 5
R43
30KR2F-GP
1 2
R56
0R2J-2-GP
1 2
U10
SN74LVC1G14DCKR-GP
NC#11
A2
GND3 Y 4
VCC 5



5
5
4
4
3
3
2
2
1
1
D D
C C
B B
A A
Power rail :P1V35(1.35V) 
Controller :TPS74801 
TDC :0.034A 
Max :0.034A 
OCP:2A 
TPS74801_1V35_BIAS
TPS74801_1V35_FB
TPS74801_1V35_OUT
TPS74801_1V35_EN
TPS74801_1V35_SS
TPS74801_P1V35_IN
P3V3_STBY
P3V3_STBY
P1V35
P1V8_STBY
P3V3_STBY
PWRGD_P1V35_PG 49
PWRGD_P1V1_PG48
Title 
Size Document Number R e v 
Date: Sheet 
o f 
Honey_Badger_uServer 1B
PWRSW_P1V35
A3
47 56Tuesday, January 20, 2015
Wiwynn Incorporated
http://www.wiwynn.com
8F, 90, Sec.1, Xintai 5th Rd., Xizhi Dist.,
New Taipei City 22102, Taiwan (R.O.C.)
Title 
Size Document Number R e v 
Date: Sheet 
o f 
Honey_Badger_uServer 1B
PWRSW_P1V35
A3
47 56Tuesday, January 20, 2015
Wiwynn Incorporated
http://www.wiwynn.com
8F, 90, Sec.1, Xintai 5th Rd., Xizhi Dist.,
New Taipei City 22102, Taiwan (R.O.C.)
Title 
Size Document Number R e v 
Date: Sheet 
o f 
Honey_Badger_uServer 1B
PWRSW_P1V35
A3
47 56Tuesday, January 20, 2015
Wiwynn Incorporated
http://www.wiwynn.com
8F, 90, Sec.1, Xintai 5th Rd., Xizhi Dist.,
New Taipei City 22102, Taiwan (R.O.C.)
PC202
SC10U6D3V5KX-4GP 
1 2
PR223
4K75R2F-1-GP
1 2
PC205
SCD1U16V2KX-3GP 
X7R
0.1uF
16V
0402
1 2
PC198 
SC10U6D3V5KX-4GP 
1 2 R379
4K75R2F-1-GP
NOPOP
1 2
PC196
SC10U6D3V5KX-4GP 
1 2
PR221
0R6J-3-GP
1 2
PR219
0R2J-2-GP
1 2
PR224
3K3R2F-2-GP
1 2
PC197
SC1KP50V2KX-1GP 
NOPOP
1 2
PC195
SCD1U16V2KX-3GP
1 2
PC194
SC470P50V2KX-3GP
1 2
PC200 
SC10U6D3V5KX-4GP 
1 2
PC193
SCD1U16V2KX-3GP
NOPOP
1 2
PU16
TPS74801RGW-GP
OUT#1 1
NC#2 2
NC#3 3
NC#4 4
IN#55 IN#66 IN#77 IN#88
PG 9
BIAS 10 
EN 11 
GND 12 
NC#13 13 
NC#14 14 
SS 15 
FB 16 
NC#17 17 
OUT#18 18
OUT#19 19
OUT#20 20
GND 21 
PR220
0R2J-2-GP
1 2
PR225
0R3J-6-GP
1 2
PC201
SC10U6D3V5KX-4GP 
1 2
PC199
SC10U6D3V5KX-4GP 
1 2
PR222
10KR2F-2-GP
12
PC203
SCD1U10V2KX-5GP
1 2



5
5
4
4
3
3
2
2
1
1
D D
C C
B B
A A
Power rail : P1V1(1.07) 
Controller : EN6337 (Fswitching=2MHz) 
TDC :2.8A 
MAX :2.8A 
OCP :5A 
VR_P1V1_VFBR
VR_P1V1_SS 
VR_P1V1_AVIN
VR_P1V1_PVIN
VR_P1V1_EN
VCCRAMCPUSI1_SENSE
TP_VDDB
TP_BGND
VR_P1V1_VFB 
P1V1
P3V3_STBY
P3V3_STBY
AGND_P1V1
P3V3_STBY
AGND_P1V1
P3V3_STBY
AGND_P1V1
PWRGD_P1V1_PG 47
PWRGD_PVCCP_VNN_PG 50
VCCRAMCPUSI1_SENSE18
Title 
Size Document Number R e v 
Date: Sheet 
o f 
Honey_Badger_uServer 1B
PWRSW_P1V1
A3
48 56Tuesday, January 20, 2015
Wiwynn Incorporated
http://www.wiwynn.com
8F, 90, Sec.1, Xintai 5th Rd., Xizhi Dist.,
New Taipei City 22102, Taiwan (R.O.C.)
Title 
Size Document Number R e v 
Date: Sheet 
o f 
Honey_Badger_uServer 1B
PWRSW_P1V1
A3
48 56Tuesday, January 20, 2015
Wiwynn Incorporated
http://www.wiwynn.com
8F, 90, Sec.1, Xintai 5th Rd., Xizhi Dist.,
New Taipei City 22102, Taiwan (R.O.C.)
Title 
Size Document Number R e v 
Date: Sheet 
o f 
Honey_Badger_uServer 1B
PWRSW_P1V1
A3
48 56Tuesday, January 20, 2015
Wiwynn Incorporated
http://www.wiwynn.com
8F, 90, Sec.1, Xintai 5th Rd., Xizhi Dist.,
New Taipei City 22102, Taiwan (R.O.C.)
PR3
0R2J-2-GP
1 2
PC21
SC10U6D3V5KX-4GP 
1 2
PR8 0R2J-2-GP 12
TP21
PC122 SCD015U25V2KX-GP
1 2
PC4
SC15P50V2GN-GP
1 2
PR4
0R2J-2-GP 
1 2
PR31
0R6J-3-GP
1 2
PC7
SC47U6D3V5MX-1-GP 
1 2
PR5
0R2J-2-GP
1 2
PG1
COPPER-CLOSE-GP-U
1 2
PC26
SC10U6D3V5KX-4GP 
1 2
PC19
SC22U10V6KX-GP 
1 2
PR6
200KR2F-L-GP
1 2
PR15
470KR2F-GP
1 2
PU1
EN6337QI-GP-U
NC#33
NC#44
VOUT#55
VOUT#66
VOUT#77
VOUT#8 8
VOUT#9 9
VFB 31 
NC#36/SW 36 
NC#35/SW 35 
NC#34/SW 34 
POK 28 
SS 30 
RLLM 29 
ENABLE 27
PVIN 19PVIN 20PVIN 21
PGND 15 
PGND 16 
NC#38/SW 38 
LLM/SYNC 26
AVIN 33 
AGND 32 
NC#37/SW 37 VOUT#10 10 
VOUT#11 11 
NC#12/SW 12 
PGND 13 
PGND 14 
NC#1/SW1
NC#2/SW2
NC#22 22NC#23 23VDDB 24
GND 39 
PGND 17 
PGND 18 
BGND 25
PR7
10KR2F-2-GP
12
TP31
PC8
SC1U10V2KX-1GP
12
PR910KR2F-2-GP NOPOP 12



5
5
4
4
3
3
2
2
1
1
D D
C C
B B
A A
Power rail :P1V0(1.0V) 
Controller :TPS53319 
Fswitch= 300KHz 
TDC : TBD 
Max : 6.9A 
OCP :8A 
P1V0_EN
P1V0_LX
P1V0_VREG
P1V0_VBST 
P1V0_ROVP 
P1V0_MODE
P1V0_VREG
PG_P1V0
P1V0_SW_R
P1V0_VFB
P1V0_VBST_RC
P1V0_MODE
P1V0_VDD
P1V0_VFB_R 
P1V0_VIN
P1V0_TRIP
P1V0_SNB
P1V0_VREG
P1V0_RF
P1V0
P1V0
AGND_P1V0
AGND_P1V0
AGND_P1V0
AGND_P1V0
P12V
AGND_P1V0
P3V3_STBY
AGND_P1V0
P1V0
PWRGD_P1V35_PG47
PWRGD_P1V0_PG42
Title 
Size Document Number R e v 
Date: Sheet 
o f 
Honey_Badger_uServer 1B
PWRSW_P1V0
A3
49 56Tuesday, January 20, 2015
Wiwynn Incorporated
http://www.wiwynn.com
8F, 90, Sec.1, Xintai 5th Rd., Xizhi Dist.,
New Taipei City 22102, Taiwan (R.O.C.)
Title 
Size Document Number R e v 
Date: Sheet 
o f 
Honey_Badger_uServer 1B
PWRSW_P1V0
A3
49 56Tuesday, January 20, 2015
Wiwynn Incorporated
http://www.wiwynn.com
8F, 90, Sec.1, Xintai 5th Rd., Xizhi Dist.,
New Taipei City 22102, Taiwan (R.O.C.)
Title 
Size Document Number R e v 
Date: Sheet 
o f 
Honey_Badger_uServer 1B
PWRSW_P1V0
A3
49 56Tuesday, January 20, 2015
Wiwynn Incorporated
http://www.wiwynn.com
8F, 90, Sec.1, Xintai 5th Rd., Xizhi Dist.,
New Taipei City 22102, Taiwan (R.O.C.)
PL8
BLM18PG330SN1D-GP
1 2
PL5
COIL-D68UH-9-GP
1 2
PC91
SC22U25V5MX-GP 
1 2
PC50
SCD1U50V3KX-GP
1 2
PU7
TPS53319DQPR-GP
VFB 1PGOOD3
EN2
VBST 4
ROVP 5
LL#6 6
LL#7 7
LL#8 8
LL#9 9
LL#10 10
LL#11 11
VIN 12 VIN 13 VIN 14 VIN 15 VIN 16 VIN 17 
VREG18
VDD19
MODE20
TRIP21
RF22
GND 23 
PR90
10KR2F-2-GP
1 2
PC44
SC22U6D3V3MX-1-GP 
1 2
PR100
3D01R5F-GP
1 2
PR84
0R2J-2-GP
12
PR79
0R5J-5-GP
1 2
PR112 100KR2F-L2-GP
NOPOP
1 2
PR114
0R3J-0-U-GP12
PR118
475KR2F-GP
1 2
PR116 78K7R2F-GP1 2
PR120
100KR2F-L1-GP
NOPOP
12
PC47
SC22U6D3V3MX-1-GP 
1 2
PR102
10D7R2F-GP
12
PC85
SC22U25V5MX-GP 
1 2
PR86
2K21R2F-GP
1 2
PR111 187KR2F-GP
NOPOP
12
PR101
10KR2F-L1-GP
NOPOP
1 2
PC89 SC1U16V2KX-GP12
PR103
6K49R2D-GP
1 2
PC51
SC22U6D3V3MX-1-GP 
1 2
PC78
SCD1U50V3KX-GP 
1 2
PTC1
SE470UF2VDM-GP
1 2
PR96 15KR2F-GP1 2
PC36
SC22U6D3V3MX-1-GP 
1 2
PC76
SC470P50V2KX-3GP
1 2
PC94
SC22U25V5MX-GP 
1 2
PC90
SC4D7U25V5KX-1-GP
1 2
PR87
0R2J-2-GP
NOPOP
1 2
PR99 0R2J-2-GP1 2
PSP1
COPPER-CLOSE-GP-U
1 2
PC81
SC22U25V5MX-GP 
1 2
PC75
SC1KP50V2KX-1GP
12
PR106
10KR2D-GP
1 2
PC64
SC1KP50V2KX-1GP
NOPOP
12
R37 0R2J-2-GP1 2
PC63
SCD1U16V2KX-3GP
1 2
PC42
SC22U6D3V3MX-1-GP 
1 2



5
5
4
4
3
3
2
2
1
1
D D
C C
B B
A A
Power rail 
:PVCCP/PVNN(0.75~1.03) 
Controller :ISL95831 
Fswitch= 450KHz 
TDC : TBD 
Max : PVCCP/23.3A & PVNN/2.2A 
OCP :28A 
Routed As Dif f e r ent ia l  P a i r 
VR_PVNN_IMON
PVCC_PVNN_EN_R
VR_PVNN_PROG2
VR_PVCCP_ISUMN 
VR_PVNN_VSEN_R
VR_PVNN_NTC 
AVV_VCCCPUVIDSIO_1P03_SENSE
VR_PVCCP_ISEN1
VR_PVCCP_ISUMP
PVCCP_ISEN2
VR_PVCCP_PVNN_VCCP
PWRGD_R_PVCCP
VR_PVCCP_RTN
VR_PVCCP_COMP
VR_PVCCP_VSEN
VR_PVNN_COMP
VR_PVNN_ISUMN_RC 
VR_PVCCP_ISUMN
SVID_CPU_CLK
VR_PVCCP_ISUMN_RC 
VR_PVCCP_IMON
VR_PVNN_COMP
VR_PVNN_ISUMN 
VR_PVNN_ISUMN_R 
VR_PVNN_ISUMP 
VR_PVCCP_PVNN_VIN
VR_PVCCP_VSEN
PVCCP_PVNN_R_VRHOT#
VR_PVCCP_ISUMN 
VR_PVCCP_RTN
VR_PVNN_FB
VR_PVCCP_PVNN_VDD
VR_PVCCP_ISUMN_R 
VR_PVCCP_IMON
VR_PVNN_VSEN
VR_PVCCP_LH_R VR_PVNN_RTN
VR_PVCCP_FB_RC2
VR_PVCCP_VSEN
VR_PVCCP_FB
VR_PVCCP_COMP_RC
VR_PVCCP_COMP VR_PVCCP_FB_RC1
VR_PVCCP_VSEN_R
VR_PVCCP_PHASE
VR_PVNN_GL
VR_PVNN_FB_RC2
VR_PVNN_VSEN
VR_PVNN_VSEN
VR_PVNN_ISUMN
VR_PVNN_ISUMP_R2 VR_PVNN_BOOT_R
VR_PVNN_GH_RVR_PVNN_GH
VR_PVNN_BOOT
VR_PVNN_ISUMN_R2 
VR_PVNN_ISUMP
VR_PVNN_VW
VR_PVCCP_VW
SVID_CPU_DATA
VR_PVNN_FB
VR_PVNN_PHASE
VR_PVCCP_GH_R
AVV_VSSCPUVIDSIO_1P03_SENSE
VR_PVNN_IMON
TP_PVCCP_VDIO
VR_PVCCP_PVNN_VDD
VR_PVCCP_ISUMP_R2 
VR_PVCCP_PROG1
VR_PVNN_COMP_RC
VR_PVNN_GH
PWRGD_R_PVNN
SVID_CPU_CLK TP_PVCCP_CLK
VR_PVCCP_BOOT_R
VR_PVCCP_COMP
VR_PVNN_COMP
TP_PVCCP_ALERTSVID_CPU_ALERT#
VR_PVNN_BOOT
VR_95831_SDA
VR_PVCCP_BOOT
SVID_CPU_DATA
VR_PVNN_GL
VR_PVCCP_ISUMP 
VR_PVCCP_FB
VR_95831_ALERT_NSVID_CPU_ALERT#
VR_PVCCP_GH
VR_95831_SCLKSVID_CPU_CLK
VR_PVCCP_GH
VR_PVCCP_PVNN_VDD 
VR_PVCCP_PHASE
VR_PVNN_FB_RC1
VR_PVCCP_BOOT
VR_PVCCP_ISUMN_R2 
VR_PVCCP_ISEN1 
VR_PVCCP_GL
VR_PVCCP_GL
VR_PVCCP_ISEN1_R
VR_PVCCP_PWM3
VR_PVNN_RTN
VR_PVCCP_VSW_R 
VR_PVCCP_PWM_OUT
VR_PVCCP_NTC 
VR_PVNN_OUTPUT
VR_PVNN_PHASE
VR_PVNN_LH_R 
VCCP_Z 
SVID_CPU_DATA
PVNN
VCCP_5VBias
VR_FET_SW_P12V_PVCCP_PVNN
PVCCP
PVCCP
PVCCP
VCCP_5VBias
PVNN
PVNN
VR_FET_SW_P12V_PVCCP_PVNN
P12V
VR_FET_SW_P12V_PVCCP_PVNN
P12V
P1V0
VCCP_5VBias
VR_FET_SW_P12V_PVCCP_PVNN
P3V3_STBY
PWRGD_PVCCP_VNN_PG48
PWRGD_PVTT_PG52
PWRGD_PVCCP_VNN_PG48
AVV_VCCCPUVIDSIO_1P03_SENSE 18
AVV_VSSCPUVIDSIO_1P03_SENSE 18
SVID_CPU_CLK15,16,51
SVID_CPU_ALERT#15,16,51
SVID_CPU_DATA15,16,51
PVCCP_PVNN_VRHOT#38,51
PMU_SLP_S3#15,16,52
Title 
Size Document Number Rev 
Date: Sheet o f 
Honey_Badger_uServer 1B
PWRSW_PVCCP & PVNN
A2
50 56Tuesday, January 20, 2015
Wiwynn Incorporated
http://www.wiwynn.com
8F, 90, Sec.1, Xintai 5th Rd., Xizhi Dist.,
New Taipei City 22102, Taiwan (R.O.C.)
Title 
Size Document Number Rev 
Date: Sheet o f 
Honey_Badger_uServer 1B
PWRSW_PVCCP & PVNN
A2
50 56Tuesday, January 20, 2015
Wiwynn Incorporated
http://www.wiwynn.com
8F, 90, Sec.1, Xintai 5th Rd., Xizhi Dist.,
New Taipei City 22102, Taiwan (R.O.C.)
Title 
Size Document Number Rev 
Date: Sheet o f 
Honey_Badger_uServer 1B
PWRSW_PVCCP & PVNN
A2
50 56Tuesday, January 20, 2015
Wiwynn Incorporated
http://www.wiwynn.com
8F, 90, Sec.1, Xintai 5th Rd., Xizhi Dist.,
New Taipei City 22102, Taiwan (R.O.C.)
PR14
1K5R2F-2-GP
1 2
PR25
0R3J-0-U-GP
1 2
PC22 
SC1KP50V2KX-1GP 
1 2
PC144
SC47U6D3V5MX-1-GP 
0805
X5R
1 2
R496
10KR2F-2-GP
1 2
PC62 
SC10U16V6KX-2GP 
1 2
PC17 
SCD022U16V2KX-3GP 
1 2
PC2
SC470P50V2KX-3GP
1 2
PR75 0R2J-2-GP 
1 2
PR95 
2K61R2F-1-GP 
1 2
PR46
10KR2F-2-GP
1 2
PR44
0R2J-2-GP
12
PR57 10KR2F-2-GP 
NOPOP 
12
PR77
180R2F-1-GP
1 2
PC33
SCD1U25V2KX-2-GP 
1 2
PR18
10R2F-L-GP
1 2
PC60
SC47U6D3V5MX-1-GP 
0805
X5R
1 2
PR63 0R2J-2-GP 12
PR88
100R3F-1-GP
1 2
PC39
SC47U6D3V5MX-1-GP 
0805
X5R
1 2
PR54
0R3J-0-U-GP
1 2
PR52
56D2R2F-GP
NOPOP
1 2
PR41
0R2J-2-GP
12
PC1
SC100P50V2JN-3GP
1 2
PC46
SCD22U16V3KX-2-GP
1 2
PR82
0R2J-2-GP
12
PD1
MM3Z5V6T1G-GP
AK
PR33
120R3F-L-GP
1 2
PC34
SC3300P50V3KX-1GP 
NOPOP
1 2
PC24
SCD22U10V2KX-1GP
1 2
PR36 1K91R2F-1-GP 
1 2
PC37
SC47U6D3V5MX-1-GP 
0805
X5R
1 2
R20 150R2J-L1-GP-U1 2
TP4
1
PC15
SCD068U16V2KX-GP
1 2
PC59
SC47U6D3V5MX-1-GP 
0805
X5R
1 2
PC6
SC47U16V0MX-GP 
X5R
47uF
16V
1210
1 2
PR117
10R2F-L-GP
1 2
PR30
5K1R2F-2-GP
1 2
PC70 
SCD22U10V2KX-1GP 
1 2
PR42 0R2J-2-GP 12
PR22
0R2J-2-GP
12
PR20
0R2J-2-GP
12
PR45
0R2J-2-GP
12
PR94
100R3F-1-GP
1 2
PR23
0R2J-2-GP
1 2
PRT1
NTC-10K-19-GP-U
12
PC38
SC47U6D3V5MX-1-GP 
0805
X5R
1 2
PC31
SC47U6D3V5MX-1-GP 
0805
X5R
1 2
PC65
SC1U16V3KX-5GP
1 2
PR50
10KR2F-2-GP
12
PR70
19K6R2D-GP
1 2
PC72
SC1KP50V2KX-1GP
1 2
PR1
100R3F-1-GP
1 2
PR74 0R2J-2-GP 
1 2
PC56
SCD22U16V3KX-2-GP
1 2
PR24
10KR2F-2-GP
12
PC61
SCD068U16V2KX-GP
NOPOP
1 2
PR12
100R3F-1-GP
1 2
TP5
1
PC57 
SC1KP50V2KX-1GP 
1 2
PC145
SC47U6D3V5MX-1-GP 
0805
X5R
1 2
PC54
SCD1U16V2KX-3GP 
X7R
0.1uF
16V
0402
1 2
PR38
0R2J-2-GP
12
PR28
1K3R2F-1-GP
1 2
PR48 0R2J-2-GP 12
PR16
3K65R2F-1-GP
1 2
PR81 10R2F-L-GP1 2
TP6
1
PR21
0R2J-2-GP
12
PR85
0R2J-2-GP
12
PR78 
120R3F-L-GP 
1 2
PC20
SC10U25V5KX-GP 
1 2
PR37 0R2J-2-GP 12
PL4
IND-300NH-8-GP
1 2
PR113
0R2J-2-GP
12
Q1 
Q2 
S1/D2 
S1/D2 
S1/D2 
G2 
S2/PGND 
D1 
D1 
D1 
G1 
Q1S 
PU2
IRFH4253DTRPBF-GP-U
5
6
7
8
10
9
4
3
2
1
PR56
0R2J-2-GP
NOPOP
12
PR11
0R2J-2-GP1 2
PR29
100R2F-L1-GP-U12
PQ2
MMBT3904TT1G-GPC
B
E
PC14
SCD01U16V2KX-3GP
1 2
G1 
D1 
D1 
D1 
G2 
S2 
S2 
S2 
D1 D2/S1 
Q1 
Q2 
PQ1
FDMC8200-GP
1
2
3
4 5
6
7
8
9 10
PR83
10R2F-L-GP
1 2
PR2
1KR2F-3-GP
12
PL1
COIL-1UH-50-GP
1 2
PR26
13K7R2F-GP
1 2
PTC4
SE470UF2VDM-GP 
1 2
PC30
SC47U6D3V5MX-1-GP 
0805
X5R
1 2
PR13
0R3J-0-U-GP
1 2
PR27
2MR2F-GP
12
PR188
2K2R2F-GP
1 2
PC28
SC47U6D3V5MX-1-GP 
0805
X5R
1 2
PC35
SC1U16V3KX-5GP
1 2
PR73 
11KR2F-L-GP 
1 2
PR39
100R2F-L1-GP-U
NOPOP
12
PR68
2M2R2J-GP
1 2
PC79
SCD01U16V2KX-3GP
1 2
PR62
0R2J-2-GP
12
PR58
0R3J-0-U-GP
1 2
PC13
SCD22U16V3KX-2-GP
1 2
PC3
SC1KP50V2KX-1GP
1 2
PC18
SC10U25V5KX-GP 
1 2
PR17 
11KR2F-L-GP 
1 2
PC12
SC47U16V0MX-GP 
X5R
47uF
16V
1210
1 2
PC9
SCD1U16V2KX-3GP
X7R
0.1uF
16V
0402
12
PC29
SC47U6D3V5MX-1-GP 
0805
X5R
1 2
PR32
2D2R5F-2-GP
NOPOP
1 2
PR89
0R2J-2-GP
12
PC58 
SC150P50V2KX-GP 
1 2
PR19
10KR2F-2-GP
1 2
PC5
SC5600P25V2KX-2-GP
1 2
PR66
7K87R2F-GP
1 2
PR108
0R2J-2-GP
12
PR35
0R2J-2-GP
1 2
PC55
SCD22U10V2KX-1GP
1 2
PC67
SC4700P50V2KX-1GP
1 2
PTC5
SE470UF2VDM-GP 
1 2
PR93
1KR2F-3-GP
12
PR49
0R2J-2-GP
12
PR47
0R2J-2-GP
1 2
PC136
SC47U6D3V5MX-1-GP 
0805
X5R
1 2
PC147
SC100P50V2JN-3GP
1 2
PC23
SC10U25V5KX-GP 
1 2
PR40 10D7R2F-GP 12
PR43
0R2J-2-GP
12
PR64
3K3R3F-GP
1 2
PC16 
SCD022U16V2KX-3GP 
1 2
PL3
COIL-D22UH-GP
PCMB042T-R22MS
1 2
PR76
5K6R2F-2-GP
1 2
PC27
SC47U6D3V5MX-1-GP 
0805
X5R
1 2
PR51
10KR2F-2-GP
12
PC68
SCD33U6D3V2KX-1-GP 
1 2
TP1
1
PR55 1K91R2F-1-GP 
1 2
PC148
SC4700P50V2KX-1GP
1 2
PC10 
SC220P50V2KX-3GP 
1 2
PC135
SC47U6D3V5MX-1-GP 
0805
X5R
1 2
PC32
SCD1U25V2KX-2-GP 
1 2
PU3
ISL95831HRTZ-T-GP
VWG1
IMONG2
PGOODG3
SDA4
ALERT#5
SCLK6
VR_ON7
PGOOD8
IMON9
VR_HOT#10
NTC11
VW12
COMP 13 
FB 14 
ISEN3/FB2 15 
ISEN2 16 
ISEN1 17 
VSEN 18 
RTN 19 
ISUMN 20 
ISUMP 21 
VDD 22 
VIN 23 
PROG1 24 
COMPG 48 
FBG 47 
VSENG 46 
RTNG 45 
ISPG 44 
ISNG 43 
NTCG 42 
PROG2 41 
BOOTG 40 
UGG 39 
PHG 38 
LGG 37 
BOOT2 36
UG2 35
PH2 34
VSSP2 33
LG2 32
VDDP 31
PWM3 30
LG1 29
VSSP1 28
PH1 27
UG1 26
BOOT1 25
GND 49 
PR69 
140R2F-GP 
1 2
PR98
3K65R2F-1-GP
1 2
PR34
5K9R2F-GP
1 2
PC48
SCD22U10V2KX-1GP
1 2
PR71
0R2J-2-GP
12



5
5
4
4
3
3
2
2
1
1
D D
C C
B B
A A
Power rail :PV_VDDR(1.5/1.35V) 
Controller :ISL6353 
Fswitch= 450KHz 
TDC : TBD 
Max : 18A 
OCP :30A 
Routed As Dif f e r ent ia l  P a i r 
VR_PVDDR_A_COMP
VR_PVDDR_A_SUMN
SVID_CPU_DATA
SVID_CPU_CLK
VR_PVDDR_A_PWM3
VR_PVDDR_A_FB
VR_PVDDR_A_VW
VR_PVDDR_A_VSEN
VSENSE_PVDDR_A_VSEN
VSENSE_PVDDR_A_VRTN
VR_PVDDRA_ISUMP1
VR_PVDDR_A_SUMN
VR_PVDDR_A_VAUTO
VR_PVDDR_A_SVID_ADDR
VR_PVDDR_A_ISEN2
VR_PVDDR_A_VDDP 
VR_PVDDRA_ISUMP1
PVDDR_VIN
VR_PVDDRA_R_IS
VR_PVDDR_A_VTT
VR_PVDDRA_ISUMP1
SVID_DIO_ASVID_CPU_DATA
VR_PVDDR_A_PSI
SVID_CLK_ASVID_CPU_CLK
VR_PVDDR_A_IAUTO
VR_PVDDR_A_NTC
SVID_A_ALERT#SVID_CPU_ALERT#
VR_PVDDR_A_GL1_BG
PWRGD_PVDDR_PG
VR_PVDDR_A_OCP
VR_PVDDR_A_VDD
VR_PVDDR_PNN_VRHOT#
VR_PVDDR_A_VDD
VR_PVDDR_A_VSEN
VR_PVDDRA_ISUMN1
VR_PVDDRA_R_ISUMN1
VR_PVDDR_A_BOOT1
VSENSE_PVDDR_A_VRTN
VR_PVDDR_A_PROG2
VR_PVDDR_A_PROG1
VR_PVDDR_A_IMON
VR_PVDDR_A_GH1
VR_PVDDR_A_FB_COMP 
ISENSE_PVDDR_A_ISEN1
VR_PVDDR_A_PHASE1
VR_PVDDR_A_GL1
ISENSE_PVDDR_A_ISEN1
VR_PVDDRA_ISUMN1
VR_PWREN_PVDDR_A
VR_PVDDR_A_SUMN_C
VR_PVDDR_A_VSW
VR_PVDDR_A_VSW_R 
VSENSE_PVDDR_A_VSEN
VR_PVDDRA_ISUMP1_R
ISENSE_PVDDR_A_ISEN1
VR_PVDDR_A_NTC_R
VR_PVDDR_A_VIN
VSENSE_PVDDR_A_VSEN_FB 
VR_PVDDR_A_GH1_R
VR_PVDDR_A_VW
VDDR_Z 
VSENSE_PVDDR_A_VRTN
VR_PVDDR_A_FB
VR_PVDDR_A_COMP
PV_VDDR
PV_VDDR
P1V0
PV_VDDR
P3V3_STBYP3V3_STBY
VDDR_5VBias
PV_VDDR
P3V3_STBY
P12V
PV_VDDR
P12V
PV_VDDR
P12V
VDDR_5VBias
PMU_SLP_S45#15,16,22,38
PWRGD_PVDDR_PG22
SVID_CPU_CLK15,16,50
SVID_CPU_DATA15,16,50
SVID_CPU_ALERT#15,16,50
PVCCP_PVNN_VRHOT#38,50
Title 
Size Document Number Rev 
Date: Sheet o f 
Honey_Badger_uServer 1B
PWRSW_PV_VDDR
A2
51 56Tuesday, January 20, 2015
Wiwynn Incorporated
http://www.wiwynn.com
8F, 90, Sec.1, Xintai 5th Rd., Xizhi Dist.,
New Taipei City 22102, Taiwan (R.O.C.)
Title 
Size Document Number Rev 
Date: Sheet o f 
Honey_Badger_uServer 1B
PWRSW_PV_VDDR
A2
51 56Tuesday, January 20, 2015
Wiwynn Incorporated
http://www.wiwynn.com
8F, 90, Sec.1, Xintai 5th Rd., Xizhi Dist.,
New Taipei City 22102, Taiwan (R.O.C.)
Title 
Size Document Number Rev 
Date: Sheet o f 
Honey_Badger_uServer 1B
PWRSW_PV_VDDR
A2
51 56Tuesday, January 20, 2015
Wiwynn Incorporated
http://www.wiwynn.com
8F, 90, Sec.1, Xintai 5th Rd., Xizhi Dist.,
New Taipei City 22102, Taiwan (R.O.C.)
PR125
6K04R2F-GP
1 2
PR213
249R2F-GP
1 2
PC111 
SC10U16V6KX-2GP 
1 2
PC175
SC10U25V5KX-GP 
1 2
PD2
MM3Z5V6T1G-GP
AK
PC162
SC22U6D3V5MX-2GP 
1 2
PR211
100R2F-L1-GP-U
1 2
R143 56D2R2F-GP1 2
PC167
SC10U6D3V3MX-GP 
1 2
PR139
4K12R2F-GP 
1 2
PC95
SCD1U25V2KX-2-GP
1 2
PR167
3K3R3F-GP
1 2
PC105
SC68P50V2JN-1GP
1 2
PC191
SC330P50V2KX-3GP
1 2
PR115
10KR2F-2-GP
NOPOP
1 2
PC179
SC10U6D3V3MX-GP 
1 2
PC69
SC3300P50V3KX-1GP 
1 2
PR217
0R2J-2-GP
1 2
PR143
0R2J-2-GP
12
PR160
0R2J-2-GP
1 2
R96 150R2J-L1-GP-U1 2
PC108
SC1KP50V2KX-1GP
1 2
PR137 0R2J-2-GP 12
PR91
10KR2F-2-GP
12
PR124
0R2J-2-GP 
12
PC190
SCD1U16V2KX-3GP
X7R
0.1uF
16V
0402
1 2
C348 SCD1U16V2KX-3GP 
1 2
PRT2
NTC-100K-11-GP-U
12
PC183
SC47U16V0MX-GP 
X5R
47uF
16V
1210
1 2
PC84
SC22U25V5MX-GP 
1 2
C75
SCD22U16V2KX-GP
1 2
PC163
SC22U6D3V5MX-2GP 
1 2
PC153
SC10U6D3V3MX-GP 
1 2
PR97
0R3J-0-U-GP
1 2
PR121
787R2F-GP
1 2
PU10
ISL6353CRTZ-GP-U
UG1 24
VDD 20 
FB2 12
VDDP 29 
PROG235
SDA1
IMON6
BOOT2 34
ADDR40
VR_HOT#7
LG2 30
GND 31
COMP10 ISEN1 15
SCLK3
UG2 33
PH1 25
RTN17
ISEN2 14
GND 41 
PH2 32
PWM3 28
VSEN16
VSET1 38
BOOT1 23
PGOOD5
ALERT#2
VW9 LG1 27
FB11
NTC 8
GND 26
VR_ON4
ISUMP19
PROG122
VIN 21 
ISUMN18
VSET2 37
ISEN3 13
OVP39
PSI36
PTC2
SE470UF2VDM-GP 
1 2
PR205
0R2J-2-GP
1 2
PR148
3K65R2F-1-GP
1 2
PR130 0R2J-2-GP
NOPOP
12
PR150
15KR2J-1-GP1 2
C351 SCD1U16V2KX-3GP 
1 2
PTC3
SE470UF2VDM-GP 
1 2
PC103
SC1KP50V2KX-1GP
1 2
PL7
BLM41PG600-GP
1 2
PR156
3K3R2F-2-GP
1 2
PC165
SC10U25V5KX-GP 
1 2
PC86 SC1KP50V2KX-1GP
NOPOP
1 2
PR119
0R2J-2-GP
1 2
PR210
11KR2F-L-GP
1 2
PC157
SC100U6D3V0MX-2GP
1 2
PR123 0R2J-2-GP 12
PR162
0R2J-2-GP
1 2
PC177
SC22U6D3V5MX-2GP 
1 2
PR104
2D2R5F-2-GP
1 2
PR215
2K61R2F-1-GP
1 2
PR161
4K99R2F-L-GP
1 2
PL2
IND-300NH-8-GP
1 2
C349 SCD1U16V2KX-3GP 
1 2
PR216
10KR2F-2-GP
1 2
PC158
SC10U6D3V3MX-GP 
1 2
PC82
SCD1U25V2KX-2-GP 
1 2
PC102
SC22U25V5MX-GP 
1 2
PC169
SC10U6D3V3MX-GP 
1 2
PR133
0R2J-2-GP
12
PR208
5M1R2J-GP
1 2
PR142 0R2J-2-GP 12
C350 SCD1U16V2KX-3GP 
1 2
PR149
1KR2F-3-GP
NOPOP
1 2
PR212
100R2F-L1-GP-U
1 2
PC166
SC22U6D3V5MX-2GP 
1 2
PC161
SC22U6D3V5MX-2GP 
1 2
PR164
10R2F-L-GP
1 2
Q1 
Q2 
S1/D2 
S1/D2 
S1/D2 
G2 
S2/PGND 
D1 
D1 
D1 
G1 
Q1S 
PU6
IRFH4253DTRPBF-GP-U
5
6
7
8
10
9
4
3
2
1
PR214
100R2F-L1-GP-U
12
PR135 
5K11R2F-L1-GP NOPOP
1 2
R497
10KR2F-2-GP
1 2
PC160
SC22U6D3V5MX-2GP 
1 2
PC178
SC10U6D3V3MX-GP 
1 2
PC109
SCD22U16V3KX-2-GP
1 2
PC106
SC1U16V3KX-5GP
1 2
PC168
SC10U6D3V3MX-GP 
1 2
PR140 
5K11R2F-L1-GP 
1 2
PC156
SC10U6D3V3MX-GP 
1 2
PR134 0R2J-2-GP 12
PR145
8K45R2F-2-GP
1 2
PC107
SCD068U16V2KX-GP
NOPOP
1 2
PQ3
MMBT3904TT1G-GPC
B
E
PG3
GAP-CLOSE-PWR-4-GP 
1 2
PR110
10KR2F-2-GP
12PR131 0R2J-2-GP 12
PR109
0R3J-0-U-GP
1 2
PG2
GAP-CLOSE-PWR-4-GP 
1 2
PC99
SC1KP50V2KX-1GP
1 2
PC154
SC10U6D3V3MX-GP 
1 2
PC87
SC1000P50V-N8-GPNOPOP
1 2
PR154
0R2J-2-GP
12
PC97
SC1KP50V2KX-1GP
1 2
PC155
SC22U6D3V5MX-2GP 
1 2
PC192
SC1500P50V2KX-2GP
1 2
PR138
10KR2F-2-GP
12
PC93
SC1U16V3KX-5GP
1 2
PC189
SCD33U6D3V2KX-1-GP
1 2
R90 100R2F-L1-GP-U1 2
PR218
10KR2F-2-GP
1 2
PC92
SC22U25V5MX-GP 
1 2
C38
SC1KP50V2KX-1GP
NOPOP
1 2
PR158 0R2J-2-GP 12
PR126 10D7R2F-GP 12
PR122
10KR2F-2-GP
NOPOP
12
PC170
SC22U6D3V5MX-2GP 
1 2
PC171
SC22U6D3V5MX-2GP 
1 2
PC180
SC100U6D3V0MX-2GP
1 2
PR141
75KR2J-GP 
1 2
PR144
20KR2F-L-GP
1 2



5
5
4
4
3
3
2
2
1
1
D D
C C
B B
A A
Power rail : PV_VTT_DDR 
VID=1/2 PVDDR_N1 (default) 
Controller : TPS51200 
TDC :  1A 
Max :  1A 
OCP :  1.5 A 
PV_VTT_DDR_EN
PV_VTT_DDR_REFIN 
PV_VTT_DDR_VIN
PV_VTT_DDR_REFO
PWRGD_PVTT_PG
PV_VTT_DDR_R_PG
PV_VTT_DDR_SNS 
PV_VTT_DDR_B_EN
PV_VTT_DDR_B_REFIN 
PV_VTT_DDR_B_VIN
PV_VTT_DDR_B_R_PG
PV_VTT_DDR_B_REFO
PV_VTT_DDR_B_SNS 
PWRGD_PVTT_PGPWRGD_PVTT_PG
PMU_SLP_INB_S3#
PVTT_DDR_EN
PMU_SLP_INA_DDRVTT#
PVTT_DDR_EN
PV_VTT_DDR_A
PV_VDDRP3V3_STBY
PV_VTT_DDR_B
PV_VDDR
P3V3_STBY
P3V3_STBY
PMU_SLP_S3#15,16,50
PMU_SLP_DDRVTT#15
PWRGD_PVTT_PG50
Title 
Size Document Number R e v 
Date: Sheet 
o f 
Honey_Badger_uServer 1B
PWR_PV_VTT_DDR
A3
52 56Tuesday, January 20, 2015
Wiwynn Incorporated
http://www.wiwynn.com
8F, 90, Sec.1, Xintai 5th Rd., Xizhi Dist.,
New Taipei City 22102, Taiwan (R.O.C.)
Title 
Size Document Number R e v 
Date: Sheet 
o f 
Honey_Badger_uServer 1B
PWR_PV_VTT_DDR
A3
52 56Tuesday, January 20, 2015
Wiwynn Incorporated
http://www.wiwynn.com
8F, 90, Sec.1, Xintai 5th Rd., Xizhi Dist.,
New Taipei City 22102, Taiwan (R.O.C.)
Title 
Size Document Number R e v 
Date: Sheet 
o f 
Honey_Badger_uServer 1B
PWR_PV_VTT_DDR
A3
52 56Tuesday, January 20, 2015
Wiwynn Incorporated
http://www.wiwynn.com
8F, 90, Sec.1, Xintai 5th Rd., Xizhi Dist.,
New Taipei City 22102, Taiwan (R.O.C.)
PR165
0R2J-2-GP
1 2
PC40
SC4D7U10V3KX-GP 
1 2
PC116
SCD1U16V2KX-3GP 
NOPOP
1 2
PR166
0R2J-2-GP
1 2
PC143
SC10U6D3V3MX-GP 
12PR59 
20KR2F-L-GP 
1 2
PC140 SC10U6D3V3MX-GP 
12
PU12
TPS51200-GP-U1
REFIN 1
VLDOIN 2
VO 3
PGND 4
VOSNS 5
VIN10
PGOOD9
GND8
EN7
REFOUT6
GND 11 
PR127
0R2J-2-GP
NOPOP
1 2
PC207
SC10U6D3V3MX-GP 
12
PC204
SC10U6D3V3MX-GP 
12
PR129
0R2J-2-GP
1 2
PC41
SC4D7U10V3KX-GP 
1 2
PC45 SC10U6D3V3MX-GP 
12 PR168 
20KR2F-L-GP 
1 2
PR65
10KR2F-2-GP
1 2
PR80 
0R3J-0-U-GP 
1 2
PR67
0R2J-2-GP
1 2
PC53
SCD1U16V2KX-3GP 
1 2
PR60
10R3F-GP
1 2
PC208 SC10U6D3V3MX-GP 
12
PC115
SC1KP50V2KX-1GP 
1 2
PR53 
20KR2F-L-GP 
1 2
PC146
SC10U6D3V3MX-GP 
12
PC119
SC10U6D3V3MX-GP 
12
PR128
0R2J-2-GP
1 2
PC142
SC10U6D3V3MX-GP 
12
PC114
SCD1U16V2KX-3GP 
1 2
PC117 SC10U6D3V3MX-GP 
12
PC118
SC10U6D3V3MX-GP 
12
PR61
10R3F-GP
1 2
PR72
0R2J-2-GP
1 2
PR170 
0R3J-0-U-GP 
1 2
PC66
SCD1U16V2KX-3GP 
NOPOP
1 2
PR169 
20KR2F-L-GP 
1 2
PC49
SC10U6D3V3MX-GP 
12
PC206
SC10U6D3V3MX-GP 
12
PC43
SC1KP50V2KX-1GP 
1 2
PC52
SC10U6D3V3MX-GP 
12
PU4
TPS51200-GP-U1
REFIN 1
VLDOIN 2
VO 3
PGND 4
VOSNS 5
VIN10
PGOOD9
GND8
EN7
REFOUT6
GND 11 
C10
SCD1U10V2KX-5GP
12
U15
SN74LVC1G08DCKR-GP
B2
A1
GND3 Y 4
VCC 5



5
5
4
4
3
3
2
2
1
1
D D
C C
B B
A A
PMU_PLTRST#
IRQ_CPU_IERR#
IRQ_CPU_LV_IERR#
PMU_PLTRST#
IRQ_MCERR#
IRQ_LV_MCERR#
CLK_GEN_PG
POWER_GOOD
P3V3
P3V3
P3V3
P3V3
P3V3
P3V3_CPU
P3V3
P3V3_STBY
IRQ_CPU_LV_IERR# 38
IRQ_LV_MCERR# 38
IRQ_MCERR#15
POWER_GOOD 38
CLK_GEN_PG22,31,32,46
IRQ_CPU_IERR#15
PMU_PLTRST#15,34,37,38
PMU_RESETBUTTON# 15
BMC_SYS_RESET#37
HOST_LV_RSTBTN#38
XDP_RST_BTN_R# 24
PMU_PWRBTN_R# 15
BMC_PWRBTN#37
FPGA_PWRBTN#38
XDP_PWRBTN# 24
Title 
Size Document Number R e v 
Date: Sheet 
o f 
Honey_Badger_uServer 1B
053 ISOLATION CIRCUITRY
A3
53 56Tuesday, January 20, 2015
Wiwynn Incorporated
http://www.wiwynn.com
8F, 90, Sec.1, Xintai 5th Rd., Xizhi Dist.,
New Taipei City 22102, Taiwan (R.O.C.)
Title 
Size Document Number R e v 
Date: Sheet 
o f 
Honey_Badger_uServer 1B
053 ISOLATION CIRCUITRY
A3
53 56Tuesday, January 20, 2015
Wiwynn Incorporated
http://www.wiwynn.com
8F, 90, Sec.1, Xintai 5th Rd., Xizhi Dist.,
New Taipei City 22102, Taiwan (R.O.C.)
Title 
Size Document Number R e v 
Date: Sheet 
o f 
Honey_Badger_uServer 1B
053 ISOLATION CIRCUITRY
A3
53 56Tuesday, January 20, 2015
Wiwynn Incorporated
http://www.wiwynn.com
8F, 90, Sec.1, Xintai 5th Rd., Xizhi Dist.,
New Taipei City 22102, Taiwan (R.O.C.)
U42
SN74LVC1G11DCKR-GP
A1
GND2
B3 Y 4VCC 5C 6
R479
4K7R2F-GP
1 2
R480
4K7R2F-GP
NOPOP
1 2
C339
SCD1U10V2KX-5GP
1 2
C337
SCD1U10V2KX-5GP
1 2
U41
SNLVC1G126DCKR-GP
OE1
A2
GND3 Y 4
VCC 5
C338
SCD1U10V2KX-5GP
1 2
R475
4K7R2F-GP
NOPOP
1 2
C335
SCD1U10V2KX-5GP
1 2
U40
SNLVC1G126DCKR-GP
OE1
A2
GND3 Y 4
VCC 5
U39
SNLVC1G126DCKR-GP
OE1
A2
GND3 Y 4
VCC 5
C336
SCD1U10V2KX-5GP
1 2
U43
SN74LVC1G11DCKR-GP
A1
GND2
B3 Y 4VCC 5C 6



5
5
4
4
3
3
2
2
1
1
D D
C C
B B
A A
BLANK 
Title 
Size 
Document Number R ev 
Date: Sheet o f 
Honey_Badger_uServer 1B
BLANK
C
54 56Tuesday, January 20, 2015
Wiwynn Incorporated
http://www.wiwynn.com
8F, 90, Sec.1, Xintai 5th Rd., Xizhi Dist.,
New Taipei City 22102, Taiwan (R.O.C.)
Title 
Size 
Document Number R ev 
Date: Sheet o f 
Honey_Badger_uServer 1B
BLANK
C
54 56Tuesday, January 20, 2015
Wiwynn Incorporated
http://www.wiwynn.com
8F, 90, Sec.1, Xintai 5th Rd., Xizhi Dist.,
New Taipei City 22102, Taiwan (R.O.C.)
Title 
Size 
Document Number R ev 
Date: Sheet o f 
Honey_Badger_uServer 1B
BLANK
C
54 56Tuesday, January 20, 2015
Wiwynn Incorporated
http://www.wiwynn.com
8F, 90, Sec.1, Xintai 5th Rd., Xizhi Dist.,
New Taipei City 22102, Taiwan (R.O.C.)



5
5
4
4
3
3
2
2
1
1
D D
C C
B B
A A
BLANK 
Title 
Size 
Document Number R ev 
Date: Sheet o f 
Honey_Badger_uServer 1B
BLANK
C
55 56Tuesday, January 20, 2015
Wiwynn
H/W R&D Dept. II
8F,90,Sec. 1,Hsin Tai Wu Rd,
Hsichih, Taipei Hsien 221, Taiwan, R.O.C
Title 
Size 
Document Number R ev 
Date: Sheet o f 
Honey_Badger_uServer 1B
BLANK
C
55 56Tuesday, January 20, 2015
Wiwynn
H/W R&D Dept. II
8F,90,Sec. 1,Hsin Tai Wu Rd,
Hsichih, Taipei Hsien 221, Taiwan, R.O.C
Title 
Size 
Document Number R ev 
Date: Sheet o f 
Honey_Badger_uServer 1B
BLANK
C
55 56Tuesday, January 20, 2015
Wiwynn
H/W R&D Dept. II
8F,90,Sec. 1,Hsin Tai Wu Rd,
Hsichih, Taipei Hsien 221, Taiwan, R.O.C



5
5
4
4
3
3
2
2
1
1
D D
C C
B B
A A
BLANK 
Title 
Size 
Document Number R ev 
Date: Sheet o f 
Honey_Badger_uServer 1B
BLANK
C
56 56Tuesday, January 20, 2015
Wiwynn
H/W R&D Dept. II
8F,90,Sec. 1,Hsin Tai Wu Rd,
Hsichih, Taipei Hsien 221, Taiwan, R.O.C
Title 
Size 
Document Number R ev 
Date: Sheet o f 
Honey_Badger_uServer 1B
BLANK
C
56 56Tuesday, January 20, 2015
Wiwynn
H/W R&D Dept. II
8F,90,Sec. 1,Hsin Tai Wu Rd,
Hsichih, Taipei Hsien 221, Taiwan, R.O.C
Title 
Size 
Document Number R ev 
Date: Sheet o f 
Honey_Badger_uServer 1B
BLANK
C
56 56Tuesday, January 20, 2015
Wiwynn
H/W R&D Dept. II
8F,90,Sec. 1,Hsin Tai Wu Rd,
Hsichih, Taipei Hsien 221, Taiwan, R.O.C